G04 ================== begin FILE IDENTIFICATION RECORD ==================*
G04 Layout Name:  13948-1b.brd*
G04 Film Name:    TSMD*
G04 File Format:  Gerber RS274X*
G04 File Origin:  Cadence Allegro 16.5-S045*
G04 Origin Date:  Thu Nov 13 15:45:59 2014*
G04 *
G04 Layer:  VIA CLASS/PASTEMASK_TOP*
G04 Layer:  PIN/PASTEMASK_TOP*
G04 Layer:  PACKAGE GEOMETRY/PASTEMASK_TOP*
G04 Layer:  DRAWING FORMAT/LAYER_PCB_STORY*
G04 Layer:  DRAWING FORMAT/LAYER_PAST_T*
G04 Layer:  BOARD GEOMETRY/PANEL_OUTLINE*
G04 *
G04 Offset:    (0.00 0.00)*
G04 Mirror:    No*
G04 Mode:      Positive*
G04 Rotation:  0*
G04 FullContactRelief:  No*
G04 UndefLineWidth:     6.00*
G04 ================== end FILE IDENTIFICATION RECORD ====================*
%FSLAX35Y35*MOIN*%
%IR0*IPPOS*OFA0.00000B0.00000*MIA0B0*SFA1.00000B1.00000*%
%AMMACRO50*
4,1,40,.013,.017,
-.013,.017,
-.013695,.016939,
-.014368,.016759,
-.015,.016464,
-.015571,.016064,
-.016064,.015571,
-.016464,.015,
-.016759,.014368,
-.016939,.013695,
-.017,.013,
-.017,-.013,
-.016939,-.013695,
-.016759,-.014368,
-.016464,-.015,
-.016064,-.015571,
-.015571,-.016064,
-.015,-.016464,
-.014368,-.016759,
-.013695,-.016939,
-.013,-.017,
.013,-.017,
.013695,-.016939,
.014368,-.016759,
.015,-.016464,
.015571,-.016064,
.016064,-.015571,
.016464,-.015,
.016759,-.014368,
.016939,-.013695,
.017,-.013,
.017,.013,
.016939,.013695,
.016759,.014368,
.016464,.015,
.016064,.015571,
.015571,.016064,
.015,.016464,
.014368,.016759,
.013695,.016939,
.013,.017,
0.0*
%
%ADD50MACRO50*%
%AMMACRO37*
4,1,40,.017,-.013,
.017,.013,
.016939,.013695,
.016759,.014368,
.016464,.015,
.016064,.015571,
.015571,.016064,
.015,.016464,
.014368,.016759,
.013695,.016939,
.013,.017,
-.013,.017,
-.013695,.016939,
-.014368,.016759,
-.015,.016464,
-.015571,.016064,
-.016064,.015571,
-.016464,.015,
-.016759,.014368,
-.016939,.013695,
-.017,.013,
-.017,-.013,
-.016939,-.013695,
-.016759,-.014368,
-.016464,-.015,
-.016064,-.015571,
-.015571,-.016064,
-.015,-.016464,
-.014368,-.016759,
-.013695,-.016939,
-.013,-.017,
.013,-.017,
.013695,-.016939,
.014368,-.016759,
.015,-.016464,
.015571,-.016064,
.016064,-.015571,
.016464,-.015,
.016759,-.014368,
.016939,-.013695,
.017,-.013,
0.0*
%
%ADD37MACRO37*%
%AMMACRO95*
4,1,3,-.0125,.025,
.0125,0.0,
-.0125,-.025,
-.0125,.025,
0.0*
%
%ADD95MACRO95*%
%ADD74R,.143X.011*%
%ADD138R,.1X.081*%
%ADD112R,.045X.11*%
%ADD82R,.055X.11*%
%ADD70R,.11X.055*%
%AMMACRO68*
4,1,3,.0125,0.0,
-.0125,-.025,
-.0125,.025,
.0125,0.0,
0.0*
%
%ADD68MACRO68*%
%ADD87C,.02*%
%ADD10C,.04*%
%ADD84C,.014*%
%AMMACRO77*
4,1,40,-.007,.004,
-.007,-.004,
-.00697,-.004347,
-.006879,-.004684,
-.006732,-.005,
-.006532,-.005286,
-.006286,-.005532,
-.006,-.005732,
-.005684,-.005879,
-.005347,-.00597,
-.005,-.006,
.005,-.006,
.005347,-.00597,
.005684,-.005879,
.006,-.005732,
.006286,-.005532,
.006532,-.005286,
.006732,-.005,
.006879,-.004684,
.00697,-.004347,
.007,-.004,
.007,.004,
.00697,.004347,
.006879,.004684,
.006732,.005,
.006532,.005286,
.006286,.005532,
.006,.005732,
.005684,.005879,
.005347,.00597,
.005,.006,
-.005,.006,
-.005347,.00597,
-.005684,.005879,
-.006,.005732,
-.006286,.005532,
-.006532,.005286,
-.006732,.005,
-.006879,.004684,
-.00697,.004347,
-.007,.004,
0.0*
%
%ADD77MACRO77*%
%ADD33C,.032*%
%ADD128R,.138X.07*%
%AMMACRO81*
4,1,40,.004,.007,
-.004,.007,
-.004347,.00697,
-.004684,.006879,
-.005,.006732,
-.005286,.006532,
-.005532,.006286,
-.005732,.006,
-.005879,.005684,
-.00597,.005347,
-.006,.005,
-.006,-.005,
-.00597,-.005347,
-.005879,-.005684,
-.005732,-.006,
-.005532,-.006286,
-.005286,-.006532,
-.005,-.006732,
-.004684,-.006879,
-.004347,-.00697,
-.004,-.007,
.004,-.007,
.004347,-.00697,
.004684,-.006879,
.005,-.006732,
.005286,-.006532,
.005532,-.006286,
.005732,-.006,
.005879,-.005684,
.00597,-.005347,
.006,-.005,
.006,.005,
.00597,.005347,
.005879,.005684,
.005732,.006,
.005532,.006286,
.005286,.006532,
.005,.006732,
.004684,.006879,
.004347,.00697,
.004,.007,
0.0*
%
%ADD81MACRO81*%
%ADD28R,.008X.06*%
%ADD83C,.016*%
%ADD127R,.135X.085*%
%ADD88C,.018*%
%ADD85C,.028*%
%ADD97R,.098X.135*%
%AMMACRO110*
4,1,46,.018,-.00177,
.017918,-.003163,
.017595,-.00452,
.017042,-.0058,
.016274,-.006965,
.015316,-.007979,
.014196,-.008812,
.012949,-.009437,
.011613,-.009836,
.010227,-.009997,
.01,-.01,
-.01,-.01,
-.01,-.00999,
-.011389,-.009868,
-.012737,-.009507,
-.014001,-.008918,
-.015143,-.008118,
-.016129,-.007132,
-.016929,-.005989,
-.017519,-.004725,
-.01788,-.003378,
-.018001,-.001989,
-.018,-.00185,
-.018,.00185,
-.017903,.003241,
-.017565,.004595,
-.016998,.005869,
-.016218,.007025,
-.015249,.008028,
-.01412,.008848,
-.012867,.009459,
-.011526,.009843,
-.010139,.009989,
-.01,.00999,
-.01,.01,
.01,.01,
.01139,.009878,
.012737,.009517,
.014002,.008928,
.015144,.008128,
.016131,.007141,
.016931,.005998,
.017521,.004734,
.017882,.003387,
.018003,.001997,
.018,.00177,
.018,-.00177,
0.0*
%
%ADD110MACRO110*%
%ADD115R,.062X.062*%
%AMMACRO113*
4,1,40,.0225,-.007,
.022378,-.008389,
.022018,-.009736,
.021428,-.011,
.020628,-.012142,
.019642,-.013128,
.0185,-.013928,
.017236,-.014518,
.015889,-.014878,
.0145,-.015,
-.0145,-.015,
-.015889,-.014878,
-.017236,-.014518,
-.0185,-.013928,
-.019642,-.013128,
-.020628,-.012142,
-.021428,-.011,
-.022018,-.009736,
-.022378,-.008389,
-.0225,-.007,
-.0225,.007,
-.022378,.008389,
-.022018,.009736,
-.021428,.011,
-.020628,.012142,
-.019642,.013128,
-.0185,.013928,
-.017236,.014518,
-.015889,.014878,
-.0145,.015,
.0145,.015,
.015889,.014878,
.017236,.014518,
.0185,.013928,
.019642,.013128,
.020628,.012142,
.021428,.011,
.022018,.009736,
.022378,.008389,
.0225,.007,
.0225,-.007,
0.0*
%
%ADD113MACRO113*%
%ADD86R,.045X.045*%
%AMMACRO40*
4,1,40,-.007,-.0225,
-.008389,-.022378,
-.009736,-.022018,
-.011,-.021428,
-.012142,-.020628,
-.013128,-.019642,
-.013928,-.0185,
-.014518,-.017236,
-.014878,-.015889,
-.015,-.0145,
-.015,.0145,
-.014878,.015889,
-.014518,.017236,
-.013928,.0185,
-.013128,.019642,
-.012142,.020628,
-.011,.021428,
-.009736,.022018,
-.008389,.022378,
-.007,.0225,
.007,.0225,
.008389,.022378,
.009736,.022018,
.011,.021428,
.012142,.020628,
.013128,.019642,
.013928,.0185,
.014518,.017236,
.014878,.015889,
.015,.0145,
.015,-.0145,
.014878,-.015889,
.014518,-.017236,
.013928,-.0185,
.013128,-.019642,
.012142,-.020628,
.011,-.021428,
.009736,-.022018,
.008389,-.022378,
.007,-.0225,
-.007,-.0225,
0.0*
%
%ADD40MACRO40*%
%AMMACRO16*
4,1,40,.011,-.007,
.011,.007,
.010939,.007695,
.010759,.008368,
.010464,.009,
.010064,.009571,
.009571,.010064,
.009,.010464,
.008368,.010759,
.007695,.010939,
.007,.011,
-.007,.011,
-.007695,.010939,
-.008368,.010759,
-.009,.010464,
-.009571,.010064,
-.010064,.009571,
-.010464,.009,
-.010759,.008368,
-.010939,.007695,
-.011,.007,
-.011,-.007,
-.010939,-.007695,
-.010759,-.008368,
-.010464,-.009,
-.010064,-.009571,
-.009571,-.010064,
-.009,-.010464,
-.008368,-.010759,
-.007695,-.010939,
-.007,-.011,
.007,-.011,
.007695,-.010939,
.008368,-.010759,
.009,-.010464,
.009571,-.010064,
.010064,-.009571,
.010464,-.009,
.010759,-.008368,
.010939,-.007695,
.011,-.007,
0.0*
%
%ADD16MACRO16*%
%AMMACRO14*
4,1,40,.007,.011,
-.007,.011,
-.007695,.010939,
-.008368,.010759,
-.009,.010464,
-.009571,.010064,
-.010064,.009571,
-.010464,.009,
-.010759,.008368,
-.010939,.007695,
-.011,.007,
-.011,-.007,
-.010939,-.007695,
-.010759,-.008368,
-.010464,-.009,
-.010064,-.009571,
-.009571,-.010064,
-.009,-.010464,
-.008368,-.010759,
-.007695,-.010939,
-.007,-.011,
.007,-.011,
.007695,-.010939,
.008368,-.010759,
.009,-.010464,
.009571,-.010064,
.010064,-.009571,
.010464,-.009,
.010759,-.008368,
.010939,-.007695,
.011,-.007,
.011,.007,
.010939,.007695,
.010759,.008368,
.010464,.009,
.010064,.009571,
.009571,.010064,
.009,.010464,
.008368,.010759,
.007695,.010939,
.007,.011,
0.0*
%
%ADD14MACRO14*%
%AMMACRO66*
4,1,40,-.023,.005,
-.023,-.005,
-.022878,-.006389,
-.022518,-.007736,
-.021928,-.009,
-.021128,-.010142,
-.020142,-.011128,
-.019,-.011928,
-.017736,-.012518,
-.016389,-.012878,
-.015,-.013,
.015,-.013,
.016389,-.012878,
.017736,-.012518,
.019,-.011928,
.020142,-.011128,
.021128,-.010142,
.021928,-.009,
.022518,-.007736,
.022878,-.006389,
.023,-.005,
.023,.005,
.022878,.006389,
.022518,.007736,
.021928,.009,
.021128,.010142,
.020142,.011128,
.019,.011928,
.017736,.012518,
.016389,.012878,
.015,.013,
-.015,.013,
-.016389,.012878,
-.017736,.012518,
-.019,.011928,
-.020142,.011128,
-.021128,.010142,
-.021928,.009,
-.022518,.007736,
-.022878,.006389,
-.023,.005,
0.0*
%
%ADD66MACRO66*%
%AMMACRO129*
4,1,40,.005,.023,
-.005,.023,
-.006389,.022878,
-.007736,.022518,
-.009,.021928,
-.010142,.021128,
-.011128,.020142,
-.011928,.019,
-.012518,.017736,
-.012878,.016389,
-.013,.015,
-.013,-.015,
-.012878,-.016389,
-.012518,-.017736,
-.011928,-.019,
-.011128,-.020142,
-.010142,-.021128,
-.009,-.021928,
-.007736,-.022518,
-.006389,-.022878,
-.005,-.023,
.005,-.023,
.006389,-.022878,
.007736,-.022518,
.009,-.021928,
.010142,-.021128,
.011128,-.020142,
.011928,-.019,
.012518,-.017736,
.012878,-.016389,
.013,-.015,
.013,.015,
.012878,.016389,
.012518,.017736,
.011928,.019,
.011128,.020142,
.010142,.021128,
.009,.021928,
.007736,.022518,
.006389,.022878,
.005,.023,
0.0*
%
%ADD129MACRO129*%
%AMMACRO22*
4,1,40,-.012,.008,
-.012,-.008,
-.011939,-.008695,
-.011759,-.009368,
-.011464,-.01,
-.011064,-.010571,
-.010571,-.011064,
-.01,-.011464,
-.009368,-.011759,
-.008695,-.011939,
-.008,-.012,
.008,-.012,
.008695,-.011939,
.009368,-.011759,
.01,-.011464,
.010571,-.011064,
.011064,-.010571,
.011464,-.01,
.011759,-.009368,
.011939,-.008695,
.012,-.008,
.012,.008,
.011939,.008695,
.011759,.009368,
.011464,.01,
.011064,.010571,
.010571,.011064,
.01,.011464,
.009368,.011759,
.008695,.011939,
.008,.012,
-.008,.012,
-.008695,.011939,
-.009368,.011759,
-.01,.011464,
-.010571,.011064,
-.011064,.010571,
-.011464,.01,
-.011759,.009368,
-.011939,.008695,
-.012,.008,
0.0*
%
%ADD22MACRO22*%
%AMMACRO31*
4,1,40,.008,.012,
-.008,.012,
-.008695,.011939,
-.009368,.011759,
-.01,.011464,
-.010571,.011064,
-.011064,.010571,
-.011464,.01,
-.011759,.009368,
-.011939,.008695,
-.012,.008,
-.012,-.008,
-.011939,-.008695,
-.011759,-.009368,
-.011464,-.01,
-.011064,-.010571,
-.010571,-.011064,
-.01,-.011464,
-.009368,-.011759,
-.008695,-.011939,
-.008,-.012,
.008,-.012,
.008695,-.011939,
.009368,-.011759,
.01,-.011464,
.010571,-.011064,
.011064,-.010571,
.011464,-.01,
.011759,-.009368,
.011939,-.008695,
.012,-.008,
.012,.008,
.011939,.008695,
.011759,.009368,
.011464,.01,
.011064,.010571,
.010571,.011064,
.01,.011464,
.009368,.011759,
.008695,.011939,
.008,.012,
0.0*
%
%ADD31MACRO31*%
%AMMACRO48*
4,1,40,-.013,-.017,
.013,-.017,
.013695,-.016939,
.014368,-.016759,
.015,-.016464,
.015571,-.016064,
.016064,-.015571,
.016464,-.015,
.016759,-.014368,
.016939,-.013695,
.017,-.013,
.017,.013,
.016939,.013695,
.016759,.014368,
.016464,.015,
.016064,.015571,
.015571,.016064,
.015,.016464,
.014368,.016759,
.013695,.016939,
.013,.017,
-.013,.017,
-.013695,.016939,
-.014368,.016759,
-.015,.016464,
-.015571,.016064,
-.016064,.015571,
-.016464,.015,
-.016759,.014368,
-.016939,.013695,
-.017,.013,
-.017,-.013,
-.016939,-.013695,
-.016759,-.014368,
-.016464,-.015,
-.016064,-.015571,
-.015571,-.016064,
-.015,-.016464,
-.014368,-.016759,
-.013695,-.016939,
-.013,-.017,
0.0*
%
%ADD48MACRO48*%
%AMMACRO24*
4,1,40,-.017,.013,
-.017,-.013,
-.016939,-.013695,
-.016759,-.014368,
-.016464,-.015,
-.016064,-.015571,
-.015571,-.016064,
-.015,-.016464,
-.014368,-.016759,
-.013695,-.016939,
-.013,-.017,
.013,-.017,
.013695,-.016939,
.014368,-.016759,
.015,-.016464,
.015571,-.016064,
.016064,-.015571,
.016464,-.015,
.016759,-.014368,
.016939,-.013695,
.017,-.013,
.017,.013,
.016939,.013695,
.016759,.014368,
.016464,.015,
.016064,.015571,
.015571,.016064,
.015,.016464,
.014368,.016759,
.013695,.016939,
.013,.017,
-.013,.017,
-.013695,.016939,
-.014368,.016759,
-.015,.016464,
-.015571,.016064,
-.016064,.015571,
-.016464,.015,
-.016759,.014368,
-.016939,.013695,
-.017,.013,
0.0*
%
%ADD24MACRO24*%
%AMMACRO17*
4,1,40,.011,-.007,
.011,.007,
.010939,.007695,
.010759,.008368,
.010464,.009,
.010064,.009571,
.009571,.010064,
.009,.010464,
.008368,.010759,
.007695,.010939,
.007,.011,
-.007,.011,
-.007695,.010939,
-.008368,.010759,
-.009,.010464,
-.009571,.010064,
-.010064,.009571,
-.010464,.009,
-.010759,.008368,
-.010939,.007695,
-.011,.007,
-.011,-.007,
-.010939,-.007695,
-.010759,-.008368,
-.010464,-.009,
-.010064,-.009571,
-.009571,-.010064,
-.009,-.010464,
-.008368,-.010759,
-.007695,-.010939,
-.007,-.011,
.007,-.011,
.007695,-.010939,
.008368,-.010759,
.009,-.010464,
.009571,-.010064,
.010064,-.009571,
.010464,-.009,
.010759,-.008368,
.010939,-.007695,
.011,-.007,
0.0*
%
%ADD17MACRO17*%
%AMMACRO15*
4,1,40,.007,.011,
-.007,.011,
-.007695,.010939,
-.008368,.010759,
-.009,.010464,
-.009571,.010064,
-.010064,.009571,
-.010464,.009,
-.010759,.008368,
-.010939,.007695,
-.011,.007,
-.011,-.007,
-.010939,-.007695,
-.010759,-.008368,
-.010464,-.009,
-.010064,-.009571,
-.009571,-.010064,
-.009,-.010464,
-.008368,-.010759,
-.007695,-.010939,
-.007,-.011,
.007,-.011,
.007695,-.010939,
.008368,-.010759,
.009,-.010464,
.009571,-.010064,
.010064,-.009571,
.010464,-.009,
.010759,-.008368,
.010939,-.007695,
.011,-.007,
.011,.007,
.010939,.007695,
.010759,.008368,
.010464,.009,
.010064,.009571,
.009571,.010064,
.009,.010464,
.008368,.010759,
.007695,.010939,
.007,.011,
0.0*
%
%ADD15MACRO15*%
%AMMACRO21*
4,1,40,-.012,.008,
-.012,-.008,
-.011939,-.008695,
-.011759,-.009368,
-.011464,-.01,
-.011064,-.010571,
-.010571,-.011064,
-.01,-.011464,
-.009368,-.011759,
-.008695,-.011939,
-.008,-.012,
.008,-.012,
.008695,-.011939,
.009368,-.011759,
.01,-.011464,
.010571,-.011064,
.011064,-.010571,
.011464,-.01,
.011759,-.009368,
.011939,-.008695,
.012,-.008,
.012,.008,
.011939,.008695,
.011759,.009368,
.011464,.01,
.011064,.010571,
.010571,.011064,
.01,.011464,
.009368,.011759,
.008695,.011939,
.008,.012,
-.008,.012,
-.008695,.011939,
-.009368,.011759,
-.01,.011464,
-.010571,.011064,
-.011064,.010571,
-.011464,.01,
-.011759,.009368,
-.011939,.008695,
-.012,.008,
0.0*
%
%ADD21MACRO21*%
%AMMACRO32*
4,1,40,.008,.012,
-.008,.012,
-.008695,.011939,
-.009368,.011759,
-.01,.011464,
-.010571,.011064,
-.011064,.010571,
-.011464,.01,
-.011759,.009368,
-.011939,.008695,
-.012,.008,
-.012,-.008,
-.011939,-.008695,
-.011759,-.009368,
-.011464,-.01,
-.011064,-.010571,
-.010571,-.011064,
-.01,-.011464,
-.009368,-.011759,
-.008695,-.011939,
-.008,-.012,
.008,-.012,
.008695,-.011939,
.009368,-.011759,
.01,-.011464,
.010571,-.011064,
.011064,-.010571,
.011464,-.01,
.011759,-.009368,
.011939,-.008695,
.012,-.008,
.012,.008,
.011939,.008695,
.011759,.009368,
.011464,.01,
.011064,.010571,
.010571,.011064,
.01,.011464,
.009368,.011759,
.008695,.011939,
.008,.012,
0.0*
%
%ADD32MACRO32*%
%AMMACRO44*
4,1,40,-.013,-.017,
.013,-.017,
.013695,-.016939,
.014368,-.016759,
.015,-.016464,
.015571,-.016064,
.016064,-.015571,
.016464,-.015,
.016759,-.014368,
.016939,-.013695,
.017,-.013,
.017,.013,
.016939,.013695,
.016759,.014368,
.016464,.015,
.016064,.015571,
.015571,.016064,
.015,.016464,
.014368,.016759,
.013695,.016939,
.013,.017,
-.013,.017,
-.013695,.016939,
-.014368,.016759,
-.015,.016464,
-.015571,.016064,
-.016064,.015571,
-.016464,.015,
-.016759,.014368,
-.016939,.013695,
-.017,.013,
-.017,-.013,
-.016939,-.013695,
-.016759,-.014368,
-.016464,-.015,
-.016064,-.015571,
-.015571,-.016064,
-.015,-.016464,
-.014368,-.016759,
-.013695,-.016939,
-.013,-.017,
0.0*
%
%ADD44MACRO44*%
%AMMACRO25*
4,1,40,-.017,.013,
-.017,-.013,
-.016939,-.013695,
-.016759,-.014368,
-.016464,-.015,
-.016064,-.015571,
-.015571,-.016064,
-.015,-.016464,
-.014368,-.016759,
-.013695,-.016939,
-.013,-.017,
.013,-.017,
.013695,-.016939,
.014368,-.016759,
.015,-.016464,
.015571,-.016064,
.016064,-.015571,
.016464,-.015,
.016759,-.014368,
.016939,-.013695,
.017,-.013,
.017,.013,
.016939,.013695,
.016759,.014368,
.016464,.015,
.016064,.015571,
.015571,.016064,
.015,.016464,
.014368,.016759,
.013695,.016939,
.013,.017,
-.013,.017,
-.013695,.016939,
-.014368,.016759,
-.015,.016464,
-.015571,.016064,
-.016064,.015571,
-.016464,.015,
-.016759,.014368,
-.016939,.013695,
-.017,.013,
0.0*
%
%ADD25MACRO25*%
%ADD76R,.011X.03*%
%ADD75R,.03X.011*%
%AMMACRO69*
4,1,3,.0125,-.025,
-.0125,0.0,
.0125,.025,
.0125,-.025,
0.0*
%
%ADD69MACRO69*%
%ADD61R,.01X.014*%
%ADD149R,.012X.05*%
%ADD145R,.05X.012*%
%ADD108R,.04X.014*%
%AMMACRO94*
4,1,3,-.0125,0.0,
.0125,.025,
.0125,-.025,
-.0125,0.0,
0.0*
%
%ADD94MACRO94*%
%ADD64R,.022X.04*%
%ADD57R,.012X.042*%
%ADD55R,.042X.012*%
%ADD35R,.06X.012*%
%ADD148R,.012X.043*%
%ADD144R,.043X.012*%
%ADD91R,.012X.06*%
%ADD46R,.016X.02*%
%ADD45R,.023X.04*%
%ADD133R,.081X.02*%
%ADD126R,.042X.014*%
%ADD125R,.014X.042*%
%ADD93R,.04X.016*%
%ADD62R,.016X.012*%
%ADD38R,.06X.014*%
%ADD18O,.014X.071*%
%ADD122R,.014X.042*%
%ADD120R,.042X.014*%
%ADD118R,.016X.04*%
%ADD99R,.012X.044*%
%ADD59R,.045X.03*%
%ADD54R,.036X.012*%
%ADD53R,.012X.036*%
%ADD23R,.014X.06*%
%ADD114R,.128X.105*%
%ADD109R,.016X.032*%
%ADD106R,.012X.036*%
%ADD103R,.06X.016*%
%ADD101R,.036X.012*%
%ADD34R,.03X.045*%
%ADD151R,.028X.03*%
%ADD135R,.016X.06*%
%ADD117R,.012X.037*%
%ADD116R,.037X.012*%
%ADD105R,.012X.046*%
%ADD102R,.046X.012*%
%AMMACRO79*
4,1,40,-.004,-.007,
.004,-.007,
.004347,-.00697,
.004684,-.006879,
.005,-.006732,
.005286,-.006532,
.005532,-.006286,
.005732,-.006,
.005879,-.005684,
.00597,-.005347,
.006,-.005,
.006,.005,
.00597,.005347,
.005879,.005684,
.005732,.006,
.005532,.006286,
.005286,.006532,
.005,.006732,
.004684,.006879,
.004347,.00697,
.004,.007,
-.004,.007,
-.004347,.00697,
-.004684,.006879,
-.005,.006732,
-.005286,.006532,
-.005532,.006286,
-.005732,.006,
-.005879,.005684,
-.00597,.005347,
-.006,.005,
-.006,-.005,
-.00597,-.005347,
-.005879,-.005684,
-.005732,-.006,
-.005532,-.006286,
-.005286,-.006532,
-.005,-.006732,
-.004684,-.006879,
-.004347,-.00697,
-.004,-.007,
0.0*
%
%ADD79MACRO79*%
%ADD73R,.093X.011*%
%AMMACRO71*
4,1,40,.007,-.004,
.007,.004,
.00697,.004347,
.006879,.004684,
.006732,.005,
.006532,.005286,
.006286,.005532,
.006,.005732,
.005684,.005879,
.005347,.00597,
.005,.006,
-.005,.006,
-.005347,.00597,
-.005684,.005879,
-.006,.005732,
-.006286,.005532,
-.006532,.005286,
-.006732,.005,
-.006879,.004684,
-.00697,.004347,
-.007,.004,
-.007,-.004,
-.00697,-.004347,
-.006879,-.004684,
-.006732,-.005,
-.006532,-.005286,
-.006286,-.005532,
-.006,-.005732,
-.005684,-.005879,
-.005347,-.00597,
-.005,-.006,
.005,-.006,
.005347,-.00597,
.005684,-.005879,
.006,-.005732,
.006286,-.005532,
.006532,-.005286,
.006732,-.005,
.006879,-.004684,
.00697,-.004347,
.007,-.004,
0.0*
%
%ADD71MACRO71*%
%ADD63R,.03X.064*%
%ADD146R,.02X.066*%
%ADD142R,.128X.107*%
%ADD137R,.012X.038*%
%ADD136R,.038X.012*%
%ADD147R,.042X.055*%
%ADD143R,.042X.037*%
%ADD78R,.128X.108*%
%ADD39R,.05X.065*%
%ADD130R,.026X.036*%
%ADD80R,.053X.063*%
%ADD72R,.065X.05*%
%ADD111R,.065X.025*%
%ADD90R,.063X.053*%
%ADD60R,.045X.09*%
%ADD119R,.025X.065*%
%ADD52R,.045X.055*%
%ADD19R,.035X.083*%
%ADD11R,.048X.016*%
%ADD131R,.055X.036*%
%ADD104R,.016X.048*%
%ADD100R,.074X.054*%
%ADD65R,.095X.06*%
%ADD58R,.13X.13*%
%ADD51R,.055X.045*%
%ADD67R,.054X.074*%
%ADD124R,.075X.045*%
%ADD47R,.063X.039*%
%ADD96R,.09X.095*%
%ADD150R,.152X.152*%
%ADD134R,.079X.071*%
%ADD132R,.065X.075*%
%ADD92R,.095X.09*%
%ADD56R,.045X.059*%
%AMMACRO43*
4,1,40,.007,.0225,
.008389,.022378,
.009736,.022018,
.011,.021428,
.012142,.020628,
.013128,.019642,
.013928,.0185,
.014518,.017236,
.014878,.015889,
.015,.0145,
.015,-.0145,
.014878,-.015889,
.014518,-.017236,
.013928,-.0185,
.013128,-.019642,
.012142,-.020628,
.011,-.021428,
.009736,-.022018,
.008389,-.022378,
.007,-.0225,
-.007,-.0225,
-.008389,-.022378,
-.009736,-.022018,
-.011,-.021428,
-.012142,-.020628,
-.013128,-.019642,
-.013928,-.0185,
-.014518,-.017236,
-.014878,-.015889,
-.015,-.0145,
-.015,.0145,
-.014878,.015889,
-.014518,.017236,
-.013928,.0185,
-.013128,.019642,
-.012142,.020628,
-.011,.021428,
-.009736,.022018,
-.008389,.022378,
-.007,.0225,
.007,.0225,
0.0*
%
%ADD43MACRO43*%
%AMMACRO20*
4,1,40,-.0225,.007,
-.022378,.008389,
-.022018,.009736,
-.021428,.011,
-.020628,.012142,
-.019642,.013128,
-.0185,.013928,
-.017236,.014518,
-.015889,.014878,
-.0145,.015,
.0145,.015,
.015889,.014878,
.017236,.014518,
.0185,.013928,
.019642,.013128,
.020628,.012142,
.021428,.011,
.022018,.009736,
.022378,.008389,
.0225,.007,
.0225,-.007,
.022378,-.008389,
.022018,-.009736,
.021428,-.011,
.020628,-.012142,
.019642,-.013128,
.0185,-.013928,
.017236,-.014518,
.015889,-.014878,
.0145,-.015,
-.0145,-.015,
-.015889,-.014878,
-.017236,-.014518,
-.0185,-.013928,
-.019642,-.013128,
-.020628,-.012142,
-.021428,-.011,
-.022018,-.009736,
-.022378,-.008389,
-.0225,-.007,
-.0225,.007,
0.0*
%
%ADD20MACRO20*%
%ADD152R,.057X.039*%
%ADD141R,.055X.069*%
%ADD123R,.035X.098*%
%ADD121R,.128X.128*%
%ADD140R,.049X.069*%
%ADD107R,.183X.183*%
%AMMACRO89*
4,1,40,.024,.012,
.024,-.012,
.023878,-.013389,
.023518,-.014736,
.022928,-.016,
.022128,-.017142,
.021142,-.018128,
.02,-.018928,
.018736,-.019518,
.017389,-.019878,
.016,-.02,
-.016,-.02,
-.017389,-.019878,
-.018736,-.019518,
-.02,-.018928,
-.021142,-.018128,
-.022128,-.017142,
-.022928,-.016,
-.023518,-.014736,
-.023878,-.013389,
-.024,-.012,
-.024,.012,
-.023878,.013389,
-.023518,.014736,
-.022928,.016,
-.022128,.017142,
-.021142,.018128,
-.02,.018928,
-.018736,.019518,
-.017389,.019878,
-.016,.02,
.016,.02,
.017389,.019878,
.018736,.019518,
.02,.018928,
.021142,.018128,
.022128,.017142,
.022928,.016,
.023518,.014736,
.023878,.013389,
.024,.012,
0.0*
%
%ADD89MACRO89*%
%ADD139R,.047X.098*%
%AMMACRO42*
4,1,40,.012,-.008,
.012,.008,
.011939,.008695,
.011759,.009368,
.011464,.01,
.011064,.010571,
.010571,.011064,
.01,.011464,
.009368,.011759,
.008695,.011939,
.008,.012,
-.008,.012,
-.008695,.011939,
-.009368,.011759,
-.01,.011464,
-.010571,.011064,
-.011064,.010571,
-.011464,.01,
-.011759,.009368,
-.011939,.008695,
-.012,.008,
-.012,-.008,
-.011939,-.008695,
-.011759,-.009368,
-.011464,-.01,
-.011064,-.010571,
-.010571,-.011064,
-.01,-.011464,
-.009368,-.011759,
-.008695,-.011939,
-.008,-.012,
.008,-.012,
.008695,-.011939,
.009368,-.011759,
.01,-.011464,
.010571,-.011064,
.011064,-.010571,
.011464,-.01,
.011759,-.009368,
.011939,-.008695,
.012,-.008,
0.0*
%
%ADD42MACRO42*%
%AMMACRO27*
4,1,40,-.008,-.012,
.008,-.012,
.008695,-.011939,
.009368,-.011759,
.01,-.011464,
.010571,-.011064,
.011064,-.010571,
.011464,-.01,
.011759,-.009368,
.011939,-.008695,
.012,-.008,
.012,.008,
.011939,.008695,
.011759,.009368,
.011464,.01,
.011064,.010571,
.010571,.011064,
.01,.011464,
.009368,.011759,
.008695,.011939,
.008,.012,
-.008,.012,
-.008695,.011939,
-.009368,.011759,
-.01,.011464,
-.010571,.011064,
-.011064,.010571,
-.011464,.01,
-.011759,.009368,
-.011939,.008695,
-.012,.008,
-.012,-.008,
-.011939,-.008695,
-.011759,-.009368,
-.011464,-.01,
-.011064,-.010571,
-.010571,-.011064,
-.01,-.011464,
-.009368,-.011759,
-.008695,-.011939,
-.008,-.012,
0.0*
%
%ADD27MACRO27*%
%AMMACRO12*
4,1,40,-.007,-.011,
.007,-.011,
.007695,-.010939,
.008368,-.010759,
.009,-.010464,
.009571,-.010064,
.010064,-.009571,
.010464,-.009,
.010759,-.008368,
.010939,-.007695,
.011,-.007,
.011,.007,
.010939,.007695,
.010759,.008368,
.010464,.009,
.010064,.009571,
.009571,.010064,
.009,.010464,
.008368,.010759,
.007695,.010939,
.007,.011,
-.007,.011,
-.007695,.010939,
-.008368,.010759,
-.009,.010464,
-.009571,.010064,
-.010064,.009571,
-.010464,.009,
-.010759,.008368,
-.010939,.007695,
-.011,.007,
-.011,-.007,
-.010939,-.007695,
-.010759,-.008368,
-.010464,-.009,
-.010064,-.009571,
-.009571,-.010064,
-.009,-.010464,
-.008368,-.010759,
-.007695,-.010939,
-.007,-.011,
0.0*
%
%ADD12MACRO12*%
%AMMACRO29*
4,1,40,-.011,.007,
-.011,-.007,
-.010939,-.007695,
-.010759,-.008368,
-.010464,-.009,
-.010064,-.009571,
-.009571,-.010064,
-.009,-.010464,
-.008368,-.010759,
-.007695,-.010939,
-.007,-.011,
.007,-.011,
.007695,-.010939,
.008368,-.010759,
.009,-.010464,
.009571,-.010064,
.010064,-.009571,
.010464,-.009,
.010759,-.008368,
.010939,-.007695,
.011,-.007,
.011,.007,
.010939,.007695,
.010759,.008368,
.010464,.009,
.010064,.009571,
.009571,.010064,
.009,.010464,
.008368,.010759,
.007695,.010939,
.007,.011,
-.007,.011,
-.007695,.010939,
-.008368,.010759,
-.009,.010464,
-.009571,.010064,
-.010064,.009571,
-.010464,.009,
-.010759,.008368,
-.010939,.007695,
-.011,.007,
0.0*
%
%ADD29MACRO29*%
%AMMACRO49*
4,1,40,.013,.017,
-.013,.017,
-.013695,.016939,
-.014368,.016759,
-.015,.016464,
-.015571,.016064,
-.016064,.015571,
-.016464,.015,
-.016759,.014368,
-.016939,.013695,
-.017,.013,
-.017,-.013,
-.016939,-.013695,
-.016759,-.014368,
-.016464,-.015,
-.016064,-.015571,
-.015571,-.016064,
-.015,-.016464,
-.014368,-.016759,
-.013695,-.016939,
-.013,-.017,
.013,-.017,
.013695,-.016939,
.014368,-.016759,
.015,-.016464,
.015571,-.016064,
.016064,-.015571,
.016464,-.015,
.016759,-.014368,
.016939,-.013695,
.017,-.013,
.017,.013,
.016939,.013695,
.016759,.014368,
.016464,.015,
.016064,.015571,
.015571,.016064,
.015,.016464,
.014368,.016759,
.013695,.016939,
.013,.017,
0.0*
%
%ADD49MACRO49*%
%AMMACRO36*
4,1,40,.017,-.013,
.017,.013,
.016939,.013695,
.016759,.014368,
.016464,.015,
.016064,.015571,
.015571,.016064,
.015,.016464,
.014368,.016759,
.013695,.016939,
.013,.017,
-.013,.017,
-.013695,.016939,
-.014368,.016759,
-.015,.016464,
-.015571,.016064,
-.016064,.015571,
-.016464,.015,
-.016759,.014368,
-.016939,.013695,
-.017,.013,
-.017,-.013,
-.016939,-.013695,
-.016759,-.014368,
-.016464,-.015,
-.016064,-.015571,
-.015571,-.016064,
-.015,-.016464,
-.014368,-.016759,
-.013695,-.016939,
-.013,-.017,
.013,-.017,
.013695,-.016939,
.014368,-.016759,
.015,-.016464,
.015571,-.016064,
.016064,-.015571,
.016464,-.015,
.016759,-.014368,
.016939,-.013695,
.017,-.013,
0.0*
%
%ADD36MACRO36*%
%AMMACRO98*
4,1,20,.1075,.0635,
.1075,.049,
.118,.049,
.118,.0395,
.1075,.0395,
.1075,-.0395,
.118,-.0395,
.118,-.049,
.1075,-.049,
.1075,-.0635,
-.1075,-.0635,
-.1075,-.049,
-.118,-.049,
-.118,-.0395,
-.1075,-.0395,
-.1075,.0395,
-.118,.0395,
-.118,.049,
-.1075,.049,
-.1075,.0635,
.1075,.0635,
0.0*
%
%ADD98MACRO98*%
%AMMACRO41*
4,1,40,.012,-.008,
.012,.008,
.011939,.008695,
.011759,.009368,
.011464,.01,
.011064,.010571,
.010571,.011064,
.01,.011464,
.009368,.011759,
.008695,.011939,
.008,.012,
-.008,.012,
-.008695,.011939,
-.009368,.011759,
-.01,.011464,
-.010571,.011064,
-.011064,.010571,
-.011464,.01,
-.011759,.009368,
-.011939,.008695,
-.012,.008,
-.012,-.008,
-.011939,-.008695,
-.011759,-.009368,
-.011464,-.01,
-.011064,-.010571,
-.010571,-.011064,
-.01,-.011464,
-.009368,-.011759,
-.008695,-.011939,
-.008,-.012,
.008,-.012,
.008695,-.011939,
.009368,-.011759,
.01,-.011464,
.010571,-.011064,
.011064,-.010571,
.011464,-.01,
.011759,-.009368,
.011939,-.008695,
.012,-.008,
0.0*
%
%ADD41MACRO41*%
%AMMACRO26*
4,1,40,-.008,-.012,
.008,-.012,
.008695,-.011939,
.009368,-.011759,
.01,-.011464,
.010571,-.011064,
.011064,-.010571,
.011464,-.01,
.011759,-.009368,
.011939,-.008695,
.012,-.008,
.012,.008,
.011939,.008695,
.011759,.009368,
.011464,.01,
.011064,.010571,
.010571,.011064,
.01,.011464,
.009368,.011759,
.008695,.011939,
.008,.012,
-.008,.012,
-.008695,.011939,
-.009368,.011759,
-.01,.011464,
-.010571,.011064,
-.011064,.010571,
-.011464,.01,
-.011759,.009368,
-.011939,.008695,
-.012,.008,
-.012,-.008,
-.011939,-.008695,
-.011759,-.009368,
-.011464,-.01,
-.011064,-.010571,
-.010571,-.011064,
-.01,-.011464,
-.009368,-.011759,
-.008695,-.011939,
-.008,-.012,
0.0*
%
%ADD26MACRO26*%
%AMMACRO13*
4,1,40,-.007,-.011,
.007,-.011,
.007695,-.010939,
.008368,-.010759,
.009,-.010464,
.009571,-.010064,
.010064,-.009571,
.010464,-.009,
.010759,-.008368,
.010939,-.007695,
.011,-.007,
.011,.007,
.010939,.007695,
.010759,.008368,
.010464,.009,
.010064,.009571,
.009571,.010064,
.009,.010464,
.008368,.010759,
.007695,.010939,
.007,.011,
-.007,.011,
-.007695,.010939,
-.008368,.010759,
-.009,.010464,
-.009571,.010064,
-.010064,.009571,
-.010464,.009,
-.010759,.008368,
-.010939,.007695,
-.011,.007,
-.011,-.007,
-.010939,-.007695,
-.010759,-.008368,
-.010464,-.009,
-.010064,-.009571,
-.009571,-.010064,
-.009,-.010464,
-.008368,-.010759,
-.007695,-.010939,
-.007,-.011,
0.0*
%
%ADD13MACRO13*%
%AMMACRO30*
4,1,40,-.011,.007,
-.011,-.007,
-.010939,-.007695,
-.010759,-.008368,
-.010464,-.009,
-.010064,-.009571,
-.009571,-.010064,
-.009,-.010464,
-.008368,-.010759,
-.007695,-.010939,
-.007,-.011,
.007,-.011,
.007695,-.010939,
.008368,-.010759,
.009,-.010464,
.009571,-.010064,
.010064,-.009571,
.010464,-.009,
.010759,-.008368,
.010939,-.007695,
.011,-.007,
.011,.007,
.010939,.007695,
.010759,.008368,
.010464,.009,
.010064,.009571,
.009571,.010064,
.009,.010464,
.008368,.010759,
.007695,.010939,
.007,.011,
-.007,.011,
-.007695,.010939,
-.008368,.010759,
-.009,.010464,
-.009571,.010064,
-.010064,.009571,
-.010464,.009,
-.010759,.008368,
-.010939,.007695,
-.011,.007,
0.0*
%
%ADD30MACRO30*%
%ADD153C,.006*%
G75*
%LPD*%
G75*
G36*
G01X24135Y307086D02*
Y328678D01*
X13899D01*
Y307086D01*
X24135D01*
G37*
G36*
G01X13899Y346903D02*
Y387753D01*
X24135D01*
Y377528D01*
X22153D01*
G03Y368928I-933J-4300D01*
G01X24135D01*
Y346903D01*
X13899D01*
G37*
G36*
G01X24135Y405953D02*
Y418778D01*
X41143D01*
Y427086D01*
X13899D01*
Y405953D01*
X24135D01*
G37*
G36*
G01X35342Y307086D02*
Y323622D01*
X26735D01*
Y307086D01*
X35342D01*
G37*
G36*
G01X57756D02*
Y323622D01*
X49149D01*
Y307086D01*
X57756D01*
G37*
G36*
G01X46549D02*
Y323622D01*
X37942D01*
Y307086D01*
X46549D01*
G37*
G36*
G01X68963D02*
Y323622D01*
X60356D01*
Y307086D01*
X68963D01*
G37*
G36*
G01X91377D02*
Y323622D01*
X82770D01*
Y307086D01*
X91377D01*
G37*
G36*
G01X80170D02*
Y323622D01*
X71563D01*
Y307086D01*
X80170D01*
G37*
G36*
G01X93975Y405978D02*
Y418778D01*
X75393D01*
Y427086D01*
X104211D01*
Y405978D01*
X93975D01*
G37*
G36*
G01X104211Y307086D02*
Y328678D01*
X93975D01*
Y307086D01*
X104211D01*
G37*
G36*
G01X93975Y346903D02*
Y368928D01*
X95957D01*
G03Y377528I933J4300D01*
G01X93975D01*
Y387728D01*
X104211D01*
Y346903D01*
X93975D01*
G37*
G36*
G01X241650Y898315D02*
X250200D01*
Y907265D01*
X241650D01*
Y898315D01*
G37*
G36*
G01Y909865D02*
X250200D01*
Y918815D01*
X241650D01*
Y909865D01*
G37*
G36*
G01X252800Y898315D02*
X261350D01*
Y907265D01*
X252800D01*
Y898315D01*
G37*
G36*
G01Y909865D02*
X261350D01*
Y918815D01*
X252800D01*
Y909865D01*
G37*
G36*
G01X1051200Y244135D02*
X1042650D01*
Y235185D01*
X1051200D01*
Y244135D01*
G37*
G36*
G01Y255685D02*
X1042650D01*
Y246735D01*
X1051200D01*
Y255685D01*
G37*
G36*
G01X1062350Y244135D02*
X1053800D01*
Y235185D01*
X1062350D01*
Y244135D01*
G37*
G36*
G01Y255685D02*
X1053800D01*
Y246735D01*
X1062350D01*
Y255685D01*
G37*
G54D100*
X671500Y516250D03*
Y531750D03*
G54D101*
X707716Y110457D03*
Y132111D03*
X735716Y110457D03*
Y132111D03*
X780668Y448125D03*
Y454031D03*
X792880Y448125D03*
Y454031D03*
X1348106Y433547D03*
X1335894D03*
X1348106Y439453D03*
X1335894D03*
G54D110*
X749700Y483000D03*
X755300Y481000D03*
Y485000D03*
X865700Y477000D03*
X871300Y475000D03*
Y479000D03*
G54D111*
X751484Y548491D03*
Y553491D03*
Y558491D03*
Y563491D03*
X771484Y548491D03*
Y563491D03*
Y558491D03*
Y553491D03*
X997274Y199578D03*
Y204578D03*
Y209578D03*
Y214578D03*
X1017274Y204578D03*
Y199578D03*
Y214578D03*
Y209578D03*
X1159934Y599672D03*
Y604672D03*
Y609672D03*
Y614672D03*
X1179934D03*
Y609672D03*
Y604672D03*
Y599672D03*
X1255000Y583000D03*
Y588000D03*
Y593000D03*
Y598000D03*
X1275000Y583000D03*
Y598000D03*
Y593000D03*
Y588000D03*
X1287372Y301500D03*
Y296500D03*
Y291500D03*
Y306500D03*
X1314872Y291500D03*
Y296500D03*
Y301500D03*
Y306500D03*
G54D102*
X708216Y112426D03*
Y114394D03*
Y116363D03*
Y118331D03*
Y120300D03*
Y122268D03*
Y124237D03*
Y126205D03*
Y128174D03*
Y130142D03*
X735216Y122268D03*
Y120300D03*
Y118331D03*
Y116363D03*
Y114394D03*
Y112426D03*
Y130142D03*
Y128174D03*
Y126205D03*
Y124237D03*
G54D120*
X837031Y396460D03*
Y399019D03*
Y401578D03*
Y404137D03*
Y406696D03*
X856517Y401578D03*
Y399019D03*
Y396460D03*
Y406696D03*
Y404137D03*
X1106725Y865166D03*
Y867725D03*
Y870284D03*
Y872843D03*
Y875402D03*
X1126211D03*
Y872843D03*
Y870284D03*
Y867725D03*
Y865166D03*
G54D121*
X846774Y401578D03*
X1035216Y884468D03*
X1116468Y870284D03*
G54D130*
X1093861Y104842D03*
Y98242D03*
X1090061D03*
Y104842D03*
G54D103*
X698818Y764644D03*
Y767204D03*
Y769764D03*
Y772324D03*
X696818Y800144D03*
Y802704D03*
Y805264D03*
Y807824D03*
X715118Y772324D03*
Y769764D03*
Y767204D03*
Y764644D03*
X713118Y807824D03*
Y805264D03*
Y802704D03*
Y800144D03*
G54D10*
X34500Y692000D03*
X56000Y7500D03*
X56804Y768220D03*
X57500Y993500D03*
X125000Y827500D03*
X314429Y294500D03*
X366555Y455500D03*
X462500Y86000D03*
X526055Y295500D03*
X1086000Y592000D03*
X1184000Y793500D03*
X1341800Y788600D03*
X1367500Y995000D03*
G54D112*
X747750Y698500D03*
X766250D03*
X842218Y691284D03*
X860718D03*
G54D140*
X1279401Y38583D03*
X1268631D03*
G54D20*
X40054Y829345D03*
X47554Y833220D03*
X40054Y837095D03*
X168495Y516875D03*
X175995Y520750D03*
X168495Y524625D03*
X198250Y789125D03*
Y796875D03*
Y810875D03*
Y803125D03*
X205750Y793000D03*
Y807000D03*
X278409Y430678D03*
X270909Y434553D03*
Y426803D03*
X757250Y461500D03*
X749750Y465375D03*
Y457625D03*
X1080518Y220224D03*
X1073018Y216349D03*
Y224099D03*
X1312260Y54737D03*
X1304760Y50862D03*
Y58612D03*
G54D104*
X706560Y876750D03*
X704000D03*
X701440D03*
Y870250D03*
X706560D03*
X724940Y464572D03*
X730060D03*
Y471072D03*
X727500D03*
X724940D03*
X788060Y871250D03*
X785500D03*
X782940D03*
Y864750D03*
X788060D03*
X1101986Y823344D03*
Y816844D03*
X1107106Y823344D03*
X1104546D03*
X1107106Y816844D03*
X1195940Y862250D03*
X1198500D03*
X1195940Y868750D03*
X1208940Y862250D03*
X1211500D03*
X1214060D03*
X1201060D03*
X1214060Y868750D03*
X1208940D03*
X1201060D03*
X1240660Y840850D03*
X1238100D03*
X1235540D03*
Y834350D03*
X1240660D03*
G54D131*
X1095006Y745402D03*
Y738906D03*
X1104230Y745402D03*
Y738906D03*
G54D11*
X33554Y844660D03*
Y849780D03*
Y847220D03*
X40054Y844660D03*
Y849780D03*
X201805Y532560D03*
Y530000D03*
Y527440D03*
X208305D03*
Y532560D03*
X201805Y545060D03*
Y542500D03*
Y539940D03*
X208305D03*
Y545060D03*
Y552940D03*
Y555500D03*
Y558060D03*
X201805D03*
Y552940D03*
X721250Y875560D03*
Y870440D03*
X727750D03*
Y873000D03*
Y875560D03*
X782750Y856060D03*
Y853500D03*
Y850940D03*
X789250D03*
Y856060D03*
X839250Y846440D03*
Y849000D03*
Y851560D03*
X832750D03*
Y846440D03*
X832250Y868560D03*
Y866000D03*
Y863440D03*
X838750D03*
Y868560D03*
X865250Y659940D03*
Y662500D03*
X858750Y659940D03*
X865250Y665060D03*
X858750D03*
X932250Y56940D03*
X925750D03*
X932250Y59500D03*
Y62060D03*
X925750D03*
X1003750Y467000D03*
Y464440D03*
Y469560D03*
X1010250Y464440D03*
Y469560D03*
G54D122*
X851892Y391835D03*
X849333D03*
X846774D03*
X844215D03*
X841656D03*
Y411321D03*
X844215D03*
X846774D03*
X849333D03*
X851892D03*
X1116468Y860541D03*
X1113909D03*
X1111350D03*
Y880027D03*
X1113909D03*
X1116468D03*
X1121586Y860541D03*
X1119027D03*
Y880027D03*
X1121586D03*
G54D113*
X761966Y183784D03*
X769466Y179909D03*
Y187659D03*
X775534Y658532D03*
X783034Y654657D03*
Y662407D03*
X885750Y56500D03*
X893250Y52625D03*
Y60375D03*
X1256250Y559000D03*
X1263750Y562875D03*
Y555125D03*
X1256350Y844100D03*
X1263850Y840225D03*
Y847975D03*
G54D30*
X63304Y717920D03*
X55304Y753920D03*
X63272Y797704D03*
X58772D03*
X67772D03*
X81304Y717920D03*
X69804Y843420D03*
X96772Y717704D03*
X92772D03*
X87804Y843420D03*
X103804Y762920D03*
X102304Y890420D03*
X127654Y312153D03*
X179500Y865700D03*
X189555Y570200D03*
X194500Y864700D03*
X199000Y887200D03*
X210000Y832700D03*
X212000Y887200D03*
X232000Y832700D03*
X228000D03*
X220000D03*
X224000D03*
X216000Y887200D03*
X225000Y890700D03*
X229500D03*
X234623Y569383D03*
X273500Y201200D03*
X313485Y248572D03*
X312555Y442700D03*
X317985Y248572D03*
X341000Y97700D03*
X347000Y116129D03*
X357429Y250200D03*
X361929D03*
X352929D03*
X361178Y985700D03*
X366429Y250200D03*
X375429D03*
X370929D03*
X379929D03*
X376000Y873200D03*
X371500D03*
X380000Y922200D03*
X375500D03*
X373678Y985700D03*
X386555Y302700D03*
X395555D03*
X384500Y873700D03*
X384000Y922200D03*
X412500Y268700D03*
X396929Y257200D03*
X400555Y302700D03*
X405555D03*
X409555D03*
X398000Y873700D03*
X424929Y253100D03*
X420429D03*
X424929Y261100D03*
X423055Y297200D03*
X418555Y302700D03*
X414055D03*
X434540Y109700D03*
X440000Y239700D03*
X433929Y261100D03*
X444778Y808700D03*
X438278D03*
X444278Y879200D03*
X458555Y296700D03*
X450778Y879200D03*
X475778Y808700D03*
X469278D03*
X473778Y879200D03*
X480278D03*
X549000Y154700D03*
X549055Y330700D03*
X558955Y371600D03*
X554955D03*
X571000Y154700D03*
X659462Y484164D03*
X682382Y126142D03*
X686432Y129712D03*
X678222Y126292D03*
X690512Y129652D03*
X704716Y151984D03*
X698968Y782684D03*
X704000Y888200D03*
X724532Y57416D03*
X720032Y65416D03*
X715716Y90484D03*
X715468Y758184D03*
X736248Y152200D03*
X731716Y151984D03*
X725748Y184200D03*
X726000Y894700D03*
X763000Y459200D03*
X767000D03*
Y475200D03*
X765998Y711254D03*
X770498D03*
X788774Y478778D03*
X779774D03*
X780500Y884700D03*
X785000D03*
X806000Y731700D03*
X838055Y273700D03*
X833555D03*
X847055D03*
X851555D03*
X856055D03*
X842555D03*
X866500Y104200D03*
X865055Y273700D03*
X860555D03*
X868820Y360080D03*
X863820D03*
X867000Y436200D03*
X862500D03*
X869468Y704984D03*
X879500Y91200D03*
X873468Y704984D03*
X919000Y55200D03*
X998000Y484200D03*
X1003000D03*
X999000Y540200D03*
X1003000D03*
X1010500Y455200D03*
X1011000Y500200D03*
X1017000Y540200D03*
X1013000D03*
X1029500Y124200D03*
X1025500Y136700D03*
X1035000Y178700D03*
X1027716Y911168D03*
X1032216D03*
X1039500Y178700D03*
X1070478Y753424D03*
X1074968Y753384D03*
X1070098Y761284D03*
X1093961Y103242D03*
X1089961D03*
X1089500Y412200D03*
X1088000Y457700D03*
X1092500D03*
X1087988Y745324D03*
X1101968Y809984D03*
X1117500Y617700D03*
X1103000Y637700D03*
X1107000D03*
X1115000D03*
X1111000Y745700D03*
X1107468Y809784D03*
X1106500Y837200D03*
X1122000Y617700D03*
X1149934Y584872D03*
X1137500Y625700D03*
X1151500Y630200D03*
X1146500Y625700D03*
X1146000Y637700D03*
X1151500D03*
X1135468Y861984D03*
X1159500Y623700D03*
X1179000Y403700D03*
X1172000Y757200D03*
X1180000D03*
X1184000D03*
X1176000D03*
X1191000Y403700D03*
X1195000D03*
X1189000Y745700D03*
X1192000Y757200D03*
X1213000Y634200D03*
X1209000D03*
X1205000D03*
X1201000D03*
X1201968Y764484D03*
X1215716Y809168D03*
X1211216D03*
X1207000Y809200D03*
X1215500Y855200D03*
X1201500D03*
X1226500Y443700D03*
X1225500Y793200D03*
X1220000Y809200D03*
X1246500Y468700D03*
X1242000D03*
X1238100Y857300D03*
X1257000Y39700D03*
X1271500Y548700D03*
X1276000Y663700D03*
X1281000Y709200D03*
X1277000Y719700D03*
X1295500Y34200D03*
X1284500Y318200D03*
X1293968Y662984D03*
X1285000Y663200D03*
X1310500Y43200D03*
X1314500D03*
X1299968Y661484D03*
X1303784Y789232D03*
X1308784D03*
X1314284D03*
X1312500Y857450D03*
X1307468Y916984D03*
X1301968D03*
X1312468D03*
X1327000Y332200D03*
X1323500Y448700D03*
Y436700D03*
X1332117Y622112D03*
X1327617D03*
X1328968Y676484D03*
X1326000Y857450D03*
X1317000D03*
X1321500D03*
X1316968Y916984D03*
X1332500Y54200D03*
X1336500Y138700D03*
X1338500Y459700D03*
X1347468Y456484D03*
X1352000Y81700D03*
X1363117Y565612D03*
X1354417Y623112D03*
G54D12*
X26504Y840720D03*
X26500Y854200D03*
X51504Y842720D03*
X66004Y830720D03*
X78004Y889720D03*
X92472Y770504D03*
X92504Y790220D03*
Y798220D03*
Y806720D03*
Y811220D03*
X138700Y666500D03*
X141004Y808220D03*
Y803720D03*
Y799720D03*
Y812720D03*
X155500Y469800D03*
X165255Y530000D03*
X157255D03*
X163255Y550500D03*
X161200Y666500D03*
X152700Y844000D03*
X168500Y457800D03*
X190500Y474800D03*
X185255Y525500D03*
X185443Y537396D03*
X194200Y869500D03*
X211223Y521183D03*
X215700Y812000D03*
X221755Y560000D03*
Y564500D03*
X240700Y423000D03*
Y427000D03*
X247200Y855500D03*
Y859500D03*
Y847500D03*
X294859Y419678D03*
X324200Y98000D03*
X319205Y313152D03*
X319129Y334500D03*
X318129Y348500D03*
Y354000D03*
X344629Y237500D03*
X359723Y463783D03*
X358723Y473783D03*
Y478283D03*
X359635Y468450D03*
X358723Y482783D03*
X379255Y330500D03*
Y335000D03*
Y339500D03*
Y344000D03*
Y357500D03*
Y362000D03*
X365005Y405270D03*
Y410000D03*
Y414500D03*
Y419000D03*
X402200Y265400D03*
X405700Y885000D03*
X410700Y915500D03*
Y911500D03*
X429200Y236500D03*
X426455Y283200D03*
Y279200D03*
X430700Y941500D03*
Y945500D03*
X458200Y117500D03*
X465700Y185000D03*
X600200Y200500D03*
Y205000D03*
Y214000D03*
Y218500D03*
X648200Y440000D03*
X656164Y436538D03*
X651700Y453000D03*
X657700Y606900D03*
Y613400D03*
X681526Y99024D03*
Y103524D03*
X685276Y94934D03*
X685286Y107744D03*
X678200Y768500D03*
X686668Y797784D03*
Y807484D03*
Y802484D03*
X707700Y59500D03*
Y72500D03*
Y68000D03*
X722700Y197500D03*
Y193500D03*
X725400Y209000D03*
X729168Y797484D03*
X727700Y887000D03*
Y882500D03*
Y899000D03*
X749200Y82500D03*
Y88500D03*
Y94500D03*
Y99500D03*
X756416Y116784D03*
Y112284D03*
X753164Y476038D03*
X772200Y668000D03*
X770200Y858000D03*
Y853500D03*
X758200Y874500D03*
X786200Y546500D03*
X786700Y553500D03*
Y561000D03*
X779200Y644500D03*
X795794Y570468D03*
Y574968D03*
Y579468D03*
X809974Y469578D03*
X821200Y853500D03*
X851200Y715500D03*
X860341Y706312D03*
X882200Y334500D03*
Y338500D03*
X946794Y51797D03*
X948200Y59500D03*
X939150Y452700D03*
X1015200Y907000D03*
X1015416Y902468D03*
X1033200Y128500D03*
X1030200Y168500D03*
Y173000D03*
X1031474Y199578D03*
Y204578D03*
Y209578D03*
X1049200Y681000D03*
Y693000D03*
Y685000D03*
Y697000D03*
Y709000D03*
Y701000D03*
Y705000D03*
X1063668Y219284D03*
X1063700Y215000D03*
X1081200Y631500D03*
Y627500D03*
Y644000D03*
Y635500D03*
Y648000D03*
Y656000D03*
Y652000D03*
Y661500D03*
Y675500D03*
Y671500D03*
X1069700Y668000D03*
Y673000D03*
X1081200Y667500D03*
Y679500D03*
Y691500D03*
Y687500D03*
Y695500D03*
Y683500D03*
Y711500D03*
Y699500D03*
Y707500D03*
Y703500D03*
Y715500D03*
Y722500D03*
Y726500D03*
Y730500D03*
X1096168Y867284D03*
Y871784D03*
X1142200Y262500D03*
Y270500D03*
Y258500D03*
Y266500D03*
X1142168Y286284D03*
X1142200Y278500D03*
X1149700Y597000D03*
X1141700Y827000D03*
X1151200Y818000D03*
X1176700Y621000D03*
X1205700Y749000D03*
X1225700Y722500D03*
Y740500D03*
X1232200Y762000D03*
Y757500D03*
Y753000D03*
X1247377Y255000D03*
Y259500D03*
X1248200Y451500D03*
Y456000D03*
X1240700Y729500D03*
X1264200Y30000D03*
X1257188Y235000D03*
X1261200Y577000D03*
X1253700Y671000D03*
Y684000D03*
X1262700Y779000D03*
X1276700Y674500D03*
Y681000D03*
X1308700Y316500D03*
X1316200Y318000D03*
X1316317Y559912D03*
Y564412D03*
Y568912D03*
Y581912D03*
X1316400Y573000D03*
X1316317Y590912D03*
Y607912D03*
Y621412D03*
Y616912D03*
X1342317Y623912D03*
X1357700Y448000D03*
G54D123*
X941260Y371535D03*
X949134D03*
X941260Y388465D03*
X949134D03*
X957008Y371535D03*
X964882D03*
X957008Y388465D03*
X964882D03*
X972756Y371535D03*
Y388465D03*
G54D141*
X1283596Y557000D03*
X1273404D03*
G54D132*
X1159934Y573276D03*
Y589068D03*
X1179934Y573276D03*
Y589068D03*
G54D150*
X1344617Y593412D03*
G54D105*
X722700Y107784D03*
X720732D03*
X718763D03*
X716795D03*
X714826D03*
X712858D03*
Y134784D03*
X714826D03*
X716795D03*
X718763D03*
X720732D03*
X722700D03*
X730574Y107784D03*
X728606D03*
X726637D03*
X724669D03*
Y134784D03*
X726637D03*
X728606D03*
X730574D03*
G54D114*
X786500Y397557D03*
Y419443D03*
X1343500Y383557D03*
Y405443D03*
G54D21*
X48004Y849720D03*
X149200Y848000D03*
X225200Y883500D03*
X243700Y851500D03*
X312723Y497183D03*
Y524683D03*
X341129Y241500D03*
X339455Y449840D03*
X355223Y486783D03*
X433700Y268500D03*
X559700Y252500D03*
X563755Y328500D03*
X648200Y457000D03*
X758700Y67500D03*
X792294Y583468D03*
X801700Y860500D03*
Y856000D03*
X845700Y868500D03*
X869700Y409500D03*
X876700Y636500D03*
X927200Y51500D03*
X1011916Y879968D03*
X1037700Y124000D03*
X1052700Y287500D03*
X1052424Y291756D03*
Y296156D03*
X1052400Y299600D03*
X1048416Y900968D03*
X1064200Y737500D03*
X1054200Y844500D03*
X1113200Y817000D03*
X1138668Y282284D03*
X1147700Y814000D03*
X1138200Y822500D03*
X1147700D03*
X1207200Y878500D03*
X1249700Y197500D03*
Y201500D03*
Y205500D03*
X1248200Y435500D03*
X1281700Y564500D03*
X1369817Y593912D03*
G54D13*
X23104Y840720D03*
X23100Y854200D03*
X48104Y842720D03*
X62604Y830720D03*
X74604Y889720D03*
X89072Y770504D03*
X89104Y790220D03*
Y798220D03*
Y806720D03*
Y811220D03*
X135300Y666500D03*
X137604Y808220D03*
Y803720D03*
Y799720D03*
Y812720D03*
X149300Y844000D03*
X165100Y457800D03*
X152100Y469800D03*
X161855Y530000D03*
X153855D03*
X159855Y550500D03*
X157800Y666500D03*
X181855Y525500D03*
X182043Y537396D03*
X187100Y474800D03*
X190800Y869500D03*
X207823Y521183D03*
X212300Y812000D03*
X218355Y560000D03*
Y564500D03*
X237300Y423000D03*
Y427000D03*
X243800Y855500D03*
Y859500D03*
Y847500D03*
X291459Y419678D03*
X320800Y98000D03*
X315805Y313152D03*
X315729Y334500D03*
X314729Y348500D03*
Y354000D03*
X341229Y237500D03*
X361605Y405270D03*
Y410000D03*
Y414500D03*
Y419000D03*
X356323Y463783D03*
X355323Y473783D03*
Y478283D03*
X356235Y468450D03*
X355323Y482783D03*
X375855Y330500D03*
Y335000D03*
Y339500D03*
Y344000D03*
Y357500D03*
Y362000D03*
X398800Y265400D03*
X402300Y885000D03*
X407300Y915500D03*
Y911500D03*
X425800Y236500D03*
X423055Y283200D03*
Y279200D03*
X427300Y941500D03*
Y945500D03*
X454800Y117500D03*
X462300Y185000D03*
X596800Y200500D03*
Y205000D03*
Y214000D03*
Y218500D03*
X644800Y440000D03*
X652764Y436538D03*
X648300Y453000D03*
X654300Y606900D03*
Y613400D03*
X674800Y768500D03*
X678126Y99024D03*
Y103524D03*
X681876Y94934D03*
X681886Y107744D03*
X683268Y797784D03*
Y807484D03*
Y802484D03*
X704300Y59500D03*
Y72500D03*
Y68000D03*
X719300Y197500D03*
Y193500D03*
X722000Y209000D03*
X724300Y887000D03*
Y882500D03*
Y899000D03*
X725768Y797484D03*
X745800Y82500D03*
Y88500D03*
Y94500D03*
Y99500D03*
X753016Y116784D03*
Y112284D03*
X749764Y476038D03*
X754800Y874500D03*
X768800Y668000D03*
X766800Y858000D03*
Y853500D03*
X782800Y546500D03*
X783300Y553500D03*
Y561000D03*
X775800Y644500D03*
X806574Y469578D03*
X792394Y570468D03*
Y574968D03*
Y579468D03*
X817800Y853500D03*
X847800Y715500D03*
X856941Y706312D03*
X878800Y334500D03*
Y338500D03*
X935750Y452700D03*
X943394Y51797D03*
X944800Y59500D03*
X1011800Y907000D03*
X1012016Y902468D03*
X1029800Y128500D03*
X1026800Y168500D03*
Y173000D03*
X1028074Y199578D03*
Y204578D03*
Y209578D03*
X1045800Y681000D03*
Y693000D03*
Y685000D03*
Y697000D03*
Y709000D03*
Y701000D03*
Y705000D03*
X1060268Y219284D03*
X1060300Y215000D03*
X1066300Y668000D03*
Y673000D03*
X1077800Y631500D03*
Y627500D03*
Y644000D03*
Y635500D03*
Y648000D03*
Y656000D03*
Y652000D03*
Y661500D03*
Y675500D03*
Y671500D03*
Y667500D03*
Y679500D03*
Y691500D03*
Y687500D03*
Y695500D03*
Y683500D03*
Y711500D03*
Y699500D03*
Y707500D03*
Y703500D03*
Y715500D03*
Y722500D03*
Y726500D03*
Y730500D03*
X1092768Y867284D03*
Y871784D03*
X1138800Y262500D03*
Y270500D03*
Y258500D03*
Y266500D03*
X1138768Y286284D03*
X1138800Y278500D03*
X1146300Y597000D03*
X1138300Y827000D03*
X1147800Y818000D03*
X1173300Y621000D03*
X1202300Y749000D03*
X1222300Y722500D03*
Y740500D03*
X1228800Y762000D03*
Y757500D03*
Y753000D03*
X1243977Y255000D03*
Y259500D03*
X1244800Y451500D03*
Y456000D03*
X1237300Y729500D03*
X1260800Y30000D03*
X1253788Y235000D03*
X1257800Y577000D03*
X1250300Y671000D03*
Y684000D03*
X1259300Y779000D03*
X1273300Y674500D03*
Y681000D03*
X1312800Y318000D03*
X1305300Y316500D03*
X1312917Y559912D03*
Y564412D03*
Y568912D03*
Y581912D03*
X1313000Y573000D03*
X1312917Y590912D03*
Y607912D03*
Y621412D03*
Y616912D03*
X1338917Y623912D03*
X1354300Y448000D03*
G54D124*
X1017000Y70081D03*
Y58919D03*
G54D142*
X1301500Y392957D03*
Y415043D03*
G54D151*
X1371572Y122170D03*
G54D106*
X710889Y107284D03*
Y135284D03*
X732543Y107284D03*
Y135284D03*
X789727Y444972D03*
X783821D03*
Y457184D03*
X789727D03*
X1344953Y430394D03*
X1339047D03*
Y442606D03*
X1344953D03*
G54D133*
X1215256Y203150D03*
Y200000D03*
Y196851D03*
Y193701D03*
Y190552D03*
Y218898D03*
Y215748D03*
Y212599D03*
Y209449D03*
Y206300D03*
Y237796D03*
Y234646D03*
Y231496D03*
Y228347D03*
Y225197D03*
Y222048D03*
Y253544D03*
Y250394D03*
Y247245D03*
Y244095D03*
Y240945D03*
Y269292D03*
Y266142D03*
Y262993D03*
Y259843D03*
Y256693D03*
Y285040D03*
Y281890D03*
Y278741D03*
Y275591D03*
Y272441D03*
Y300788D03*
Y297638D03*
Y294489D03*
Y291339D03*
Y288189D03*
Y319685D03*
Y316536D03*
Y313386D03*
Y310237D03*
Y307087D03*
Y303937D03*
Y335434D03*
Y332284D03*
Y329134D03*
Y325985D03*
Y322835D03*
Y351182D03*
Y348032D03*
Y344882D03*
Y341733D03*
Y338583D03*
Y366930D03*
Y363780D03*
Y360630D03*
Y357481D03*
Y354331D03*
Y376378D03*
Y373229D03*
Y370079D03*
X1232776Y203150D03*
Y200000D03*
Y196851D03*
Y193701D03*
Y190552D03*
Y218898D03*
Y215748D03*
Y212599D03*
Y209449D03*
Y206300D03*
Y237796D03*
Y234646D03*
Y231496D03*
Y228347D03*
Y225197D03*
Y222048D03*
Y253544D03*
Y250394D03*
Y247245D03*
Y244095D03*
Y240945D03*
Y269292D03*
Y266142D03*
Y262993D03*
Y259843D03*
Y256693D03*
Y285040D03*
Y281890D03*
Y278741D03*
Y275591D03*
Y272441D03*
Y300788D03*
Y297638D03*
Y294489D03*
Y291339D03*
Y288189D03*
Y319685D03*
Y316536D03*
Y313386D03*
Y310237D03*
Y307087D03*
Y303937D03*
Y335434D03*
Y332284D03*
Y329134D03*
Y325985D03*
Y322835D03*
Y351182D03*
Y348032D03*
Y344882D03*
Y341733D03*
Y338583D03*
Y366930D03*
Y363780D03*
Y360630D03*
Y357481D03*
Y354331D03*
Y376378D03*
Y373229D03*
Y370079D03*
G54D31*
X71804Y793920D03*
X175500Y906700D03*
X171500D03*
X190800Y467000D03*
X186800D03*
X238455Y565800D03*
X309500Y88200D03*
X328555Y506700D03*
X324555D03*
X347023Y505983D03*
X373500Y14700D03*
X377000D03*
X367500Y869700D03*
X380500Y14700D03*
X594500Y240200D03*
X651964Y440738D03*
X685748Y99700D03*
X683055Y262700D03*
X687055D03*
X706500Y859700D03*
X711500Y68200D03*
X714055Y262700D03*
X718055D03*
X724000Y478700D03*
X729748Y180700D03*
X738117Y544668D03*
X742517D03*
X743000Y571700D03*
X771000Y455700D03*
X806274Y438778D03*
X792774Y475278D03*
X849500Y432700D03*
X857500Y649200D03*
X904500Y67700D03*
X984260Y195207D03*
X988660D03*
X1097500Y789200D03*
X1118300Y753200D03*
X1110468Y846984D03*
X1122800Y753200D03*
X1150258Y753394D03*
X1156768Y753484D03*
X1164200Y753400D03*
X1173000Y386700D03*
X1209470Y565210D03*
X1226500Y432200D03*
X1242100Y821800D03*
X1254000Y692200D03*
X1250500D03*
X1273000Y716200D03*
X1358617Y562112D03*
X1371617D03*
X1367617D03*
G54D22*
X51604Y849720D03*
X152800Y848000D03*
X228800Y883500D03*
X247300Y851500D03*
X316323Y497183D03*
Y524683D03*
X344729Y241500D03*
X343055Y449840D03*
X358823Y486783D03*
X437300Y268500D03*
X563300Y252500D03*
X567355Y328500D03*
X651800Y457000D03*
X762300Y67500D03*
X795894Y583468D03*
X805300Y860500D03*
Y856000D03*
X849300Y868500D03*
X873300Y409500D03*
X880300Y636500D03*
X930800Y51500D03*
X1015516Y879968D03*
X1041300Y124000D03*
X1052016Y900968D03*
X1056300Y287500D03*
X1056024Y291756D03*
Y296156D03*
X1056000Y299600D03*
X1067800Y737500D03*
X1057800Y844500D03*
X1116800Y817000D03*
X1142268Y282284D03*
X1151300Y814000D03*
X1141800Y822500D03*
X1151300D03*
X1210800Y878500D03*
X1253300Y197500D03*
Y201500D03*
Y205500D03*
X1251800Y435500D03*
X1285300Y564500D03*
X1373417Y593912D03*
G54D40*
X143500Y680750D03*
X139625Y673250D03*
X147375D03*
X143500Y695960D03*
X139625Y688460D03*
X147375D03*
X163000Y680750D03*
X159125Y673250D03*
X166875D03*
X163000Y696460D03*
X159125Y688960D03*
X166875D03*
X747748Y187250D03*
X743873Y179750D03*
X751623D03*
X873125Y615472D03*
X880875D03*
X877000Y622972D03*
X1181125Y861750D03*
X1188875D03*
X1185000Y869250D03*
G54D115*
X786774Y451078D03*
X1342000Y436500D03*
G54D41*
X155600Y465300D03*
X177543Y537396D03*
X193800Y848000D03*
X200800Y431500D03*
X320793Y450373D03*
X321823Y483783D03*
X336729Y241500D03*
X386300Y947000D03*
X472855Y301500D03*
Y305500D03*
X580300Y66000D03*
Y62000D03*
X631800Y575000D03*
X677386Y107874D03*
X690548Y122500D03*
X694762Y455464D03*
X713300Y568000D03*
X719800Y864000D03*
X785300Y355500D03*
X775574Y475078D03*
X800574D03*
X822800Y368500D03*
X821300Y849500D03*
X852800Y385000D03*
X849800Y638500D03*
X941250Y448700D03*
X1020300Y277500D03*
Y281500D03*
X1011300Y480500D03*
X1015516Y898468D03*
X1033300Y137000D03*
X1050800Y930000D03*
X1077229Y73758D03*
X1096268Y863284D03*
X1105300Y776500D03*
Y772500D03*
X1143300Y862000D03*
X1210300Y432500D03*
X1205800Y753000D03*
X1202268Y807784D03*
Y804284D03*
X1253800Y699500D03*
X1275800Y564500D03*
X1308300Y855000D03*
Y858500D03*
X1316417Y603912D03*
X1340300Y452000D03*
X1357800D03*
G54D107*
X721716Y121284D03*
G54D152*
X1369720Y117145D03*
Y110415D03*
X1390004Y117145D03*
Y110415D03*
G54D134*
X1203830Y576840D03*
Y596840D03*
X1220370Y576840D03*
Y596840D03*
G54D143*
X1312500Y14200D03*
Y19800D03*
X1321000Y14200D03*
Y19800D03*
G54D116*
X780718Y450094D03*
Y452062D03*
X792830Y450094D03*
Y452062D03*
X1348056Y437484D03*
Y435516D03*
X1335944D03*
Y437484D03*
G54D23*
X45270Y901388D03*
X47770D03*
X50270D03*
Y921988D03*
X47770D03*
X45270D03*
X62637Y729959D03*
X65197D03*
Y752049D03*
X62637D03*
X66612Y808104D03*
X64052D03*
X61492D03*
X58932D03*
Y820904D03*
X61492D03*
X64052D03*
X66612D03*
X67453Y853207D03*
Y875297D03*
X52770Y901388D03*
X55270D03*
X57770D03*
X60270D03*
X62770D03*
X65270D03*
Y921988D03*
X62770D03*
X60270D03*
X57770D03*
X55270D03*
X52770D03*
X67757Y729959D03*
X70317D03*
X72872D03*
X75432D03*
X77992D03*
X80552D03*
X83112D03*
Y752049D03*
X80552D03*
X77992D03*
X75432D03*
X72872D03*
X70317D03*
X67757D03*
X70013Y853207D03*
X72573D03*
X75133D03*
X77688D03*
X80248D03*
X82808D03*
Y875297D03*
X80248D03*
X77688D03*
X75133D03*
X72573D03*
X70013D03*
X67770Y901388D03*
X70270D03*
X72770D03*
Y921988D03*
X70270D03*
X67770D03*
X85672Y729959D03*
X88227D03*
X90787D03*
X93347D03*
X95907D03*
Y752049D03*
X93347D03*
X90787D03*
X88227D03*
X85672D03*
X85368Y853207D03*
X87928D03*
X90488D03*
X93043D03*
X95603D03*
X98163D03*
Y875297D03*
X95603D03*
X93043D03*
X90488D03*
X87928D03*
X85368D03*
X100723Y853207D03*
Y875297D03*
X104054Y901420D03*
X106554D03*
X109054D03*
X111554D03*
X114054D03*
X116554D03*
Y922020D03*
X114054D03*
X111554D03*
X109054D03*
X106554D03*
X104054D03*
X119054Y901420D03*
X121554D03*
X124054D03*
X126554D03*
X129054D03*
X131554D03*
Y922020D03*
X129054D03*
X126554D03*
X124054D03*
X121554D03*
X119054D03*
X341250Y921700D03*
X343750D03*
X346250D03*
Y942300D03*
X343750D03*
X341250D03*
X348750Y921700D03*
X351250D03*
X353750D03*
X356250D03*
X358750D03*
X361250D03*
Y942300D03*
X358750D03*
X356250D03*
X353750D03*
X351250D03*
X348750D03*
X363750Y921700D03*
X366250D03*
X368750D03*
Y942300D03*
X366250D03*
X363750D03*
X393250Y922200D03*
X395750D03*
Y942800D03*
X393250D03*
X398250Y922200D03*
X400750D03*
X403250D03*
X405750D03*
X408250D03*
X410750D03*
Y942800D03*
X408250D03*
X405750D03*
X403250D03*
X400750D03*
X398250D03*
X413250Y922200D03*
X415750D03*
X418250D03*
X420750D03*
Y942800D03*
X418250D03*
X415750D03*
X413250D03*
X558495Y339988D03*
X555935D03*
X553375D03*
X550815D03*
Y356168D03*
X553375D03*
X555935D03*
X558495D03*
X994660Y513600D03*
X997220D03*
X999780D03*
X1002340D03*
Y526400D03*
X999780D03*
X997220D03*
X994660D03*
X1008660Y513600D03*
X1011220D03*
X1013780D03*
X1016340D03*
Y526400D03*
X1013780D03*
X1011220D03*
X1008660D03*
X1182660Y373910D03*
Y390090D03*
X1190340Y373910D03*
X1187780D03*
X1185220D03*
Y390090D03*
X1187780D03*
X1190340D03*
G54D125*
X1035216Y874725D03*
X1032657D03*
X1030098D03*
Y894211D03*
X1032657D03*
X1035216D03*
X1040334Y874725D03*
X1037775D03*
Y894211D03*
X1040334D03*
G54D32*
X71804Y797520D03*
X175500Y910300D03*
X171500D03*
X190800Y470600D03*
X186800D03*
X238455Y569400D03*
X309500Y91800D03*
X328555Y510300D03*
X324555D03*
X347023Y509583D03*
X373500Y18300D03*
X377000D03*
X367500Y873300D03*
X380500Y18300D03*
X594500Y243800D03*
X651964Y444338D03*
X685748Y103300D03*
X683055Y266300D03*
X687055D03*
X706500Y863300D03*
X711500Y71800D03*
X714055Y266300D03*
X718055D03*
X724000Y482300D03*
X729748Y184300D03*
X738117Y548268D03*
X742517D03*
X743000Y575300D03*
X771000Y459300D03*
X806274Y442378D03*
X792774Y478878D03*
X849500Y436300D03*
X857500Y652800D03*
X904500Y71300D03*
X984260Y198807D03*
X988660D03*
X1097500Y792800D03*
X1118300Y756800D03*
X1110468Y850584D03*
X1122800Y756800D03*
X1150258Y756994D03*
X1156768Y757084D03*
X1164200Y757000D03*
X1173000Y390300D03*
X1209470Y568810D03*
X1226500Y435800D03*
X1242100Y825400D03*
X1254000Y695800D03*
X1250500D03*
X1273000Y719800D03*
X1358617Y565712D03*
X1371617D03*
X1367617D03*
G54D14*
X23104Y845220D03*
Y849720D03*
X30104Y885720D03*
X55104Y830720D03*
X56104Y872720D03*
Y877720D03*
Y868220D03*
Y882220D03*
X74604Y885720D03*
X89104Y815220D03*
X99104Y882720D03*
X116454Y316453D03*
Y320953D03*
X101104Y844220D03*
X138300Y283500D03*
X136300Y312000D03*
X143300Y666500D03*
X137604Y791720D03*
Y783720D03*
X152100Y474300D03*
X172600Y457800D03*
X181855Y530000D03*
X190300Y840000D03*
Y844000D03*
Y856500D03*
X186800Y865500D03*
X190800Y878500D03*
X237300Y419000D03*
Y431000D03*
X243300Y835500D03*
X243800Y863500D03*
X260959Y425678D03*
Y430178D03*
Y434678D03*
X269300Y884500D03*
X312823Y507683D03*
X320800Y93500D03*
X317323Y464283D03*
Y459783D03*
X317293Y454373D03*
X318323Y479783D03*
Y475283D03*
X343800Y884500D03*
Y878500D03*
Y893000D03*
X361355Y385000D03*
Y376000D03*
Y380500D03*
Y371000D03*
X361615Y400500D03*
X361355Y394000D03*
Y389500D03*
X351300Y884500D03*
Y878500D03*
Y893000D03*
Y889000D03*
X375855Y312500D03*
Y317000D03*
Y321500D03*
Y326000D03*
Y348500D03*
Y353000D03*
Y366500D03*
Y371000D03*
Y375500D03*
X376823Y387783D03*
X375075Y403780D03*
X375105Y408500D03*
Y417500D03*
Y413000D03*
Y426500D03*
Y422000D03*
Y431000D03*
Y435500D03*
X402300Y880500D03*
X421300Y268000D03*
X423055Y287200D03*
Y275200D03*
X438840Y106000D03*
Y110000D03*
X431840Y117500D03*
X438800Y244000D03*
X446300Y106000D03*
Y110000D03*
Y114500D03*
X457800Y277500D03*
Y273000D03*
X459800Y282000D03*
X462729Y165500D03*
Y172500D03*
Y180500D03*
X462300Y197000D03*
X462229Y189500D03*
X462300Y286500D03*
X469355Y293800D03*
X596800Y209500D03*
Y223000D03*
Y227500D03*
X635800Y453000D03*
X628300Y579000D03*
Y588500D03*
Y584000D03*
X627800Y606900D03*
Y612900D03*
X652764Y432538D03*
X644800Y444500D03*
X648300Y448500D03*
X673966Y94544D03*
X691016Y137784D03*
X704300Y63500D03*
X698800Y863500D03*
X722832Y100532D03*
X709800Y576500D03*
Y582000D03*
Y572000D03*
X724300Y864000D03*
X731548Y189500D03*
X724800Y455500D03*
X736264Y558538D03*
Y563538D03*
X737800Y553500D03*
X740268Y768784D03*
X732768D03*
Y763984D03*
X725768Y806284D03*
Y801984D03*
X753800Y82500D03*
Y88500D03*
Y94500D03*
Y99500D03*
X749764Y471538D03*
X752300Y571000D03*
Y575500D03*
X758800Y51500D03*
Y55500D03*
Y59500D03*
Y63500D03*
X762800Y138500D03*
Y134000D03*
X762700Y144300D03*
X775800Y649000D03*
X776300Y668000D03*
X796800Y471000D03*
X795800Y546500D03*
Y553500D03*
Y561000D03*
X801800Y851000D03*
X821300Y873000D03*
X835300Y858000D03*
X869800Y414000D03*
Y404500D03*
X865800Y467500D03*
X856800Y711000D03*
X872800Y101500D03*
X873800Y467500D03*
X917300Y70500D03*
X908800D03*
X983574Y204578D03*
Y209578D03*
Y214578D03*
X994300Y496500D03*
X1029800Y133000D03*
X1028074Y214078D03*
X1025016Y866968D03*
X1037800Y119500D03*
Y128500D03*
X1045800Y713000D03*
X1062768Y227284D03*
X1060268Y223284D03*
X1064300Y733500D03*
Y741500D03*
X1075268Y200784D03*
X1099300Y428000D03*
X1125800Y278000D03*
X1129800Y618000D03*
X1138800Y274500D03*
X1137800Y618000D03*
X1139768Y858284D03*
X1181300Y237000D03*
Y244000D03*
Y248000D03*
X1192477Y238000D03*
Y242500D03*
Y247500D03*
Y252500D03*
X1192468Y264060D03*
Y268560D03*
X1186300Y359000D03*
Y363500D03*
X1200300Y605500D03*
X1188800Y875500D03*
X1214584Y432532D03*
X1213800Y444000D03*
X1213270Y568510D03*
X1214800Y735500D03*
Y731000D03*
X1222300Y718500D03*
Y735500D03*
Y731000D03*
X1221800Y831500D03*
X1247477Y241500D03*
Y245500D03*
X1244300Y268500D03*
Y272500D03*
X1248300Y431500D03*
Y427500D03*
X1240300Y593000D03*
Y598000D03*
X1245800Y661000D03*
X1244300Y762000D03*
X1253788Y221500D03*
Y226000D03*
Y230500D03*
X1250300Y643000D03*
Y647000D03*
Y639000D03*
Y635000D03*
Y651000D03*
Y657000D03*
X1257800Y661000D03*
Y657000D03*
Y651000D03*
X1250300Y667000D03*
X1257800Y667500D03*
X1250300Y680000D03*
Y688000D03*
Y707500D03*
Y703500D03*
Y711500D03*
X1259300Y783000D03*
X1261900Y835100D03*
X1312917Y586412D03*
Y595412D03*
Y612412D03*
Y599912D03*
X1327300Y298000D03*
Y293000D03*
X1343917Y567412D03*
X1338917Y619412D03*
X1358800Y106000D03*
X1354300Y456000D03*
X1369917Y589912D03*
Y585412D03*
Y597912D03*
Y602412D03*
Y611412D03*
Y606912D03*
G54D50*
X189800Y861000D03*
X193300Y852000D03*
X193800Y874000D03*
X215300Y816500D03*
X458229Y101500D03*
X602198Y426116D03*
Y431116D03*
Y441116D03*
Y436116D03*
Y451116D03*
Y446116D03*
X676548Y56500D03*
Y63500D03*
X725000Y202000D03*
X769574Y441078D03*
X852300Y720000D03*
X875768Y709784D03*
X1044300Y105500D03*
Y111000D03*
X1106300Y780500D03*
X1152700Y604700D03*
X1254800Y716000D03*
X1293300Y363000D03*
X1308300Y564500D03*
X1330800Y420000D03*
X1317417Y577412D03*
X1342417Y562412D03*
G54D153*
G01X-185516Y-508119D02*
Y-490619D01*
G01X-176346D02*
Y-508119D01*
G01Y-499369D02*
X-185516D01*
G01X-163431Y-508119D02*
X-165178Y-507827D01*
X-166706Y-506661D01*
X-168016Y-504911D01*
X-168890Y-502869D01*
X-169326Y-500536D01*
Y-498202D01*
X-168890Y-495869D01*
X-168016Y-493827D01*
X-166706Y-492078D01*
X-165178Y-490911D01*
X-163431Y-490619D01*
X-161685Y-490911D01*
X-160156Y-492078D01*
X-158846Y-493827D01*
X-157972Y-495869D01*
X-157536Y-498202D01*
Y-500536D01*
X-157972Y-502869D01*
X-158846Y-504911D01*
X-160156Y-506661D01*
X-161685Y-507827D01*
X-163431Y-508119D01*
G01X-150953D02*
Y-490619D01*
X-140909Y-508119D01*
Y-490619D01*
G01X-124064Y-508119D02*
X-132798D01*
Y-490619D01*
X-124064D01*
G01X-127558Y-499077D02*
X-132798D01*
G01X-110931Y-508119D02*
Y-500244D01*
X-115298Y-490619D01*
G01X-106564D02*
X-110931Y-500244D01*
G01X-74185Y-498786D02*
X-73311Y-497911D01*
X-72656Y-496453D01*
X-72219Y-494410D01*
X-72656Y-492661D01*
X-73529Y-491494D01*
X-75058Y-490619D01*
X-80953D01*
Y-508119D01*
X-73748D01*
X-72219Y-506953D01*
X-71346Y-505202D01*
X-70909Y-503161D01*
X-71346Y-501119D01*
X-72656Y-499369D01*
X-74185Y-498786D01*
X-80953D01*
G01X-63890Y-508119D02*
X-58431Y-490619D01*
X-52972Y-508119D01*
G01X-54938Y-501994D02*
X-61925D01*
G01X-45734Y-508119D02*
Y-490619D01*
X-41368D01*
X-39621Y-491494D01*
X-38311Y-492661D01*
X-37219Y-494410D01*
X-36346Y-496453D01*
X-36128Y-499369D01*
X-36346Y-502286D01*
X-37219Y-504328D01*
X-38311Y-506078D01*
X-39621Y-507244D01*
X-41368Y-508119D01*
X-45734D01*
G01X-22121Y-499369D02*
X-17754D01*
Y-504619D01*
X-19064Y-506369D01*
X-20593Y-507536D01*
X-22776Y-508119D01*
X-24959Y-507536D01*
X-26488Y-506369D01*
X-27798Y-504619D01*
X-28671Y-502577D01*
X-29108Y-500244D01*
Y-498202D01*
X-28671Y-496453D01*
X-27798Y-494410D01*
X-26488Y-492661D01*
X-25178Y-491494D01*
X-23431Y-490619D01*
X-21903D01*
X-20156Y-491202D01*
X-18846Y-492369D01*
G01X-1564Y-508119D02*
X-10298D01*
Y-490619D01*
X-1564D01*
G01X-5058Y-499077D02*
X-10298D01*
G01X7202Y-508119D02*
Y-490619D01*
X12661D01*
X14407Y-491494D01*
X15499Y-492661D01*
X15936Y-494994D01*
X15499Y-497328D01*
X14189Y-498786D01*
X12661Y-499661D01*
X7202D01*
G01X12661D02*
X15936Y-508119D01*
G01X48315Y-498786D02*
X49189Y-497911D01*
X49844Y-496453D01*
X50281Y-494410D01*
X49844Y-492661D01*
X48971Y-491494D01*
X47442Y-490619D01*
X41547D01*
Y-508119D01*
X48752D01*
X50281Y-506953D01*
X51154Y-505202D01*
X51591Y-503161D01*
X51154Y-501119D01*
X49844Y-499369D01*
X48315Y-498786D01*
X41547D01*
G01X58610Y-508119D02*
X64069Y-490619D01*
X69528Y-508119D01*
G01X67562Y-501994D02*
X60575D01*
G01X76984Y-505786D02*
X78731Y-507244D01*
X80696Y-508119D01*
X82442D01*
X84189Y-507244D01*
X85499Y-505786D01*
X86154Y-503744D01*
X85717Y-501703D01*
X84626Y-499952D01*
X82661Y-498786D01*
X80041Y-498202D01*
X78512Y-497036D01*
X77857Y-494994D01*
X78294Y-492952D01*
X79386Y-491494D01*
X80914Y-490619D01*
X82442D01*
X83971Y-491202D01*
X85281Y-492661D01*
G01X103436Y-508119D02*
X94702D01*
Y-490619D01*
X103436D01*
G01X99942Y-499077D02*
X94702D01*
G01X118315Y-498786D02*
X119189Y-497911D01*
X119844Y-496453D01*
X120281Y-494410D01*
X119844Y-492661D01*
X118971Y-491494D01*
X117442Y-490619D01*
X111547D01*
Y-508119D01*
X118752D01*
X120281Y-506953D01*
X121154Y-505202D01*
X121591Y-503161D01*
X121154Y-501119D01*
X119844Y-499369D01*
X118315Y-498786D01*
X111547D01*
G01X134069Y-508119D02*
X132322Y-507827D01*
X130794Y-506661D01*
X129484Y-504911D01*
X128610Y-502869D01*
X128174Y-500536D01*
Y-498202D01*
X128610Y-495869D01*
X129484Y-493827D01*
X130794Y-492078D01*
X132322Y-490911D01*
X134069Y-490619D01*
X135815Y-490911D01*
X137344Y-492078D01*
X138654Y-493827D01*
X139528Y-495869D01*
X139964Y-498202D01*
Y-500536D01*
X139528Y-502869D01*
X138654Y-504911D01*
X137344Y-506661D01*
X135815Y-507827D01*
X134069Y-508119D01*
G01X146110D02*
X151569Y-490619D01*
X157028Y-508119D01*
G01X155062Y-501994D02*
X148075D01*
G01X164702Y-508119D02*
Y-490619D01*
X170161D01*
X171907Y-491494D01*
X172999Y-492661D01*
X173436Y-494994D01*
X172999Y-497328D01*
X171689Y-498786D01*
X170161Y-499661D01*
X164702D01*
G01X170161D02*
X173436Y-508119D01*
G01X181766D02*
Y-490619D01*
X186132D01*
X187879Y-491494D01*
X189189Y-492661D01*
X190281Y-494410D01*
X191154Y-496453D01*
X191372Y-499369D01*
X191154Y-502286D01*
X190281Y-504328D01*
X189189Y-506078D01*
X187879Y-507244D01*
X186132Y-508119D01*
X181766D01*
G01X-37858Y-463119D02*
Y-445619D01*
X-32181Y-460202D01*
X-26504Y-445619D01*
Y-463119D01*
G01X-14681D02*
X-15991Y-462827D01*
X-17301Y-461661D01*
X-18175Y-459619D01*
X-18611Y-457286D01*
X-18175Y-454952D01*
X-17301Y-452911D01*
X-15991Y-451744D01*
X-14681Y-451453D01*
X-13371Y-451744D01*
X-12061Y-452911D01*
X-11188Y-454952D01*
X-10969Y-457286D01*
X-11188Y-459619D01*
X-12061Y-461661D01*
X-13371Y-462827D01*
X-14681Y-463119D01*
G01X6749Y-445619D02*
Y-463119D01*
G01Y-460495D02*
X5876Y-461953D01*
X4565Y-462827D01*
X3037Y-463119D01*
X1291Y-462536D01*
X-19Y-461078D01*
X-893Y-459328D01*
X-1111Y-457286D01*
X-893Y-455244D01*
X-19Y-453494D01*
X1291Y-452036D01*
X3037Y-451453D01*
X4565Y-451744D01*
X5657Y-452328D01*
X6749Y-453494D01*
G01X17044Y-455244D02*
X24031D01*
X23376Y-453202D01*
X22284Y-452036D01*
X20756Y-451453D01*
X19227Y-451744D01*
X17917Y-452619D01*
X17044Y-454661D01*
X16607Y-456411D01*
Y-458161D01*
X17044Y-459911D01*
X18136Y-461661D01*
X19446Y-462827D01*
X20974Y-463119D01*
X22502Y-462536D01*
X24031Y-460786D01*
G01X37819Y-463119D02*
Y-445619D01*
G01X1Y-17717D02*
G03X7875Y-25591I7874J0D01*
G01X1Y299252D02*
Y-10394D01*
G01Y-17717D02*
G03X7875Y-25591I7874J0D01*
G01X1Y299252D02*
Y-10394D01*
G01Y-17717D02*
Y-10394D01*
G01D02*
Y-17723D01*
G01X0Y11811D02*
Y0D01*
G01X92520Y299252D02*
X1D01*
G01X92520D02*
X1D01*
G01X0Y318937D02*
G03X11811Y307126I11811J0D01*
G01X0Y968503D02*
Y318937D01*
G01X19685Y988189D02*
G03X0Y968503I0J-19685D01*
G01X43950Y996063D02*
X1D01*
G01X43950D02*
X1D01*
G01Y1008622D02*
Y996063D01*
G01Y1008622D02*
Y996063D01*
G01X15001Y1023622D02*
G03X1Y1008622I0J-15000D01*
G01X15001Y1023622D02*
G03X1Y1008622I0J-15000D01*
G01X7875Y-25591D02*
X45337D01*
G01X7875D02*
X45337D01*
G01X11811Y307126D02*
X100394D01*
G01X10710Y1008622D02*
G03X19292I4291J0D01*
G01D02*
G03X10710I-4291J0D01*
G01X99804Y1023622D02*
X15001D01*
G01X99804D02*
X15001D01*
G01X103740Y988189D02*
X19685D01*
G01X53211Y-25591D02*
G03X45337I-3937J0D01*
G01X53211D02*
G03X45337I-3937J0D01*
G01X53211D02*
G03X45337I-3937J0D01*
G01X53211D02*
G03X45337I-3937J0D01*
G01X43950Y988189D02*
G03Y996063I0J3937D01*
G01Y988189D02*
G03Y996063I0J3937D01*
G01X53211Y-25591D02*
X1392127D01*
G01X53211D02*
X1392127D01*
G01X69147Y996063D02*
G03Y988189I0J-3937D01*
G01Y996063D02*
G03Y988189I0J-3937D01*
G01X99804Y996063D02*
X69147D01*
G01X99804D02*
X69147D01*
G01X94412Y72220D02*
G03X85830Y72219I-4291J-1D01*
G01D02*
G03X94412Y72220I4291J0D01*
G01X100394Y291377D02*
G03X92520Y299252I-7874J1D01*
G01X100394Y291377D02*
G03X92520Y299252I-7874J1D01*
G01X99804Y1023622D02*
Y996063D01*
G01Y1023622D02*
Y996063D01*
G01X100394Y236259D02*
G03X116142Y220511I15748J0D01*
G01D02*
X232088D01*
G01X100394Y236259D02*
G03X116142Y220511I15748J0D01*
G01D02*
X232088D01*
G01X116142Y228385D02*
X239961D01*
G01X108268Y236259D02*
G03X116142Y228385I7874J0D01*
G01X108268Y299252D02*
Y236259D01*
G01X100395Y240899D02*
X100394Y236259D01*
G01X100395Y240899D02*
X100394Y236259D01*
G01X108269Y240899D02*
G03X100395I-3937J0D01*
G01X108269D02*
G03X100395I-3937J0D01*
G01Y266096D02*
G03X108269I3937J-1D01*
G01X100395D02*
G03X108269I3937J-1D01*
G01X100395D02*
X100394Y291377D01*
G01X100395Y266096D02*
X100394Y291377D01*
G01X108268Y299252D02*
G03X100394Y307126I-7874J0D01*
G01X103740Y988189D02*
G03X107677Y992126I0J3937D01*
G01Y1018109D02*
Y992126D01*
G01X136024Y1018109D02*
X136023Y1021653D01*
X134055Y1023622D01*
X109645D01*
X107677Y1021653D01*
Y1018109D01*
G01X136024Y994290D02*
G03X143505I3740J0D01*
G01X136024D02*
Y1018109D01*
G01X143504D02*
Y994290D01*
G01X187598Y1018109D02*
Y1021653D01*
X185630Y1023622D01*
X145472D01*
X143504Y1021653D01*
Y1018109D01*
G01X151575Y220511D02*
X226378D01*
G01X151575D02*
X226378D01*
G01X187598Y992126D02*
Y1018109D01*
G01Y992126D02*
G03X191535Y988189I3937J0D01*
G01X261220D02*
X191535D01*
G01X212681Y996063D02*
X195473D01*
G01D02*
Y1023622D01*
G01X212681Y996063D02*
X195473D01*
G01D02*
Y1023622D01*
G01D02*
X257284D01*
G01X195473D02*
X257284D01*
G01X212681Y988189D02*
G03Y996063I0J3937D01*
G01Y988189D02*
G03Y996063I0J3937D01*
G01X222751Y1008622D02*
G03X231333I4291J0D01*
G01D02*
G03X222751I-4291J0D01*
G01X243898Y70866D02*
G03X247835Y66928I3937J-1D01*
G01X243898Y224448D02*
Y70866D01*
G01X236025Y164487D02*
Y70866D01*
G01D02*
G03X247836Y59055I11811J0D01*
G01X236025Y164487D02*
Y70866D01*
G01D02*
G03X247836Y59055I11811J0D01*
G01X243899Y164487D02*
G03X236025I-3937J0D01*
G01X243899D02*
G03X236025I-3937J0D01*
G01Y189684D02*
G03X243899I3937J0D01*
G01X236025D02*
G03X243899I3937J0D01*
G01X236025D02*
Y216574D01*
G01Y189684D02*
Y216574D01*
G01D02*
G03X232088Y220511I-3937J0D01*
G01X236025Y216574D02*
G03X232088Y220511I-3937J0D01*
G01X243898Y224448D02*
G03X239961Y228385I-3937J0D01*
G01X237877Y996063D02*
G03Y988189I0J-3937D01*
G01Y996063D02*
G03Y988189I0J-3937D01*
G01X257284Y996063D02*
X237877D01*
G01X257284D02*
X237877D01*
G01X247835Y66929D02*
X289174D01*
G01X247836Y59055D02*
X285237D01*
G01X247836D02*
X285237D01*
G01X261220Y988189D02*
G03X265157Y992126I0J3937D01*
G01X257284Y1023622D02*
Y996063D01*
G01Y1023622D02*
Y996063D01*
G01X281019Y-508119D02*
Y-490619D01*
X278399Y-494119D01*
G01Y-508119D02*
X283639D01*
G01X293716Y-504619D02*
X295025Y-506661D01*
X296772Y-507827D01*
X298737Y-508119D01*
X300484Y-507827D01*
X302231Y-506369D01*
X303322Y-504619D01*
X303541Y-502869D01*
X303104Y-500828D01*
X301576Y-499369D01*
X300047Y-498786D01*
X298082D01*
G01X300047D02*
X301357Y-497911D01*
X302449Y-496453D01*
X302886Y-494703D01*
X302449Y-492952D01*
X301357Y-491494D01*
X299392Y-490619D01*
X297427Y-490911D01*
X295462Y-492078D01*
G01X312307Y-506078D02*
X313836Y-507536D01*
X315582Y-508119D01*
X317329Y-507536D01*
X318857Y-505786D01*
X319949Y-503161D01*
X320386Y-500536D01*
Y-497328D01*
X319949Y-494703D01*
X318857Y-492369D01*
X317547Y-491202D01*
X316019Y-490619D01*
X314272Y-491202D01*
X312962Y-492369D01*
X312089Y-494119D01*
X311652Y-496453D01*
X312089Y-498494D01*
X313181Y-500536D01*
X314491Y-501703D01*
X316019Y-501994D01*
X317765Y-501411D01*
X319076Y-499952D01*
X320386Y-497328D01*
G01X336139Y-508119D02*
Y-490619D01*
X328060Y-503161D01*
X338978D01*
G01X351019Y-508119D02*
X352547Y-507827D01*
X354294Y-506953D01*
X355386Y-505495D01*
X355822Y-503452D01*
X355386Y-501411D01*
X354076Y-499661D01*
X352111Y-498786D01*
X349927D01*
X348617Y-498202D01*
X347525Y-496744D01*
X347089Y-494703D01*
X347744Y-492661D01*
X349272Y-491202D01*
X351019Y-490619D01*
X352765Y-491202D01*
X354294Y-492661D01*
X354949Y-494703D01*
X354512Y-496744D01*
X353421Y-498202D01*
X352111Y-498786D01*
X349927D01*
X347962Y-499661D01*
X346652Y-501411D01*
X346216Y-503452D01*
X346652Y-505495D01*
X347744Y-506953D01*
X349491Y-507827D01*
X351019Y-508119D01*
G01X267902Y-463119D02*
Y-445619D01*
X273142D01*
X274889Y-446494D01*
X276199Y-448536D01*
X276636Y-450869D01*
X276199Y-453202D01*
X275107Y-454952D01*
X273142Y-455828D01*
X267902D01*
G01X294572Y-447078D02*
X293262Y-446202D01*
X291734Y-445619D01*
X289987D01*
X288022Y-446494D01*
X286494Y-447952D01*
X285402Y-449703D01*
X284529Y-452619D01*
X284310Y-455244D01*
X284747Y-457869D01*
X285402Y-459619D01*
X286712Y-461369D01*
X288241Y-462536D01*
X289769Y-463119D01*
X291297D01*
X292826Y-462536D01*
X294136Y-461661D01*
X295228Y-460495D01*
G01X309015Y-453786D02*
X309889Y-452911D01*
X310544Y-451453D01*
X310981Y-449410D01*
X310544Y-447661D01*
X309671Y-446494D01*
X308142Y-445619D01*
X302247D01*
Y-463119D01*
X309452D01*
X310981Y-461953D01*
X311854Y-460202D01*
X312291Y-458161D01*
X311854Y-456119D01*
X310544Y-454369D01*
X309015Y-453786D01*
X302247D01*
G01X318219Y-468952D02*
X331319D01*
G01X337247Y-463119D02*
Y-445619D01*
X347291Y-463119D01*
Y-445619D01*
G01X359769Y-463119D02*
X358022Y-462827D01*
X356494Y-461661D01*
X355184Y-459911D01*
X354310Y-457869D01*
X353874Y-455536D01*
Y-453202D01*
X354310Y-450869D01*
X355184Y-448827D01*
X356494Y-447078D01*
X358022Y-445911D01*
X359769Y-445619D01*
X361515Y-445911D01*
X363044Y-447078D01*
X364354Y-448827D01*
X365228Y-450869D01*
X365664Y-453202D01*
Y-455536D01*
X365228Y-457869D01*
X364354Y-459911D01*
X363044Y-461661D01*
X361515Y-462827D01*
X359769Y-463119D01*
G01X265157Y1018109D02*
Y992126D01*
G01X545472Y1018109D02*
Y1021653D01*
X543504Y1023622D01*
X267126D01*
X265157Y1021653D01*
Y1018109D01*
G01X293111Y3937D02*
G03X297047Y0I3937J0D01*
G01X293110Y62992D02*
Y3937D01*
G01X285237D02*
G03X297048Y-7874I11811J0D01*
G01X285237Y59055D02*
Y3937D01*
G01D02*
G03X297048Y-7874I11811J0D01*
G01X285237Y59055D02*
Y3937D01*
G01X293111Y62992D02*
G03X289174Y66929I-3937J0D01*
G01X297047Y0D02*
X1108209D01*
G01X297037Y-7874D02*
X301187D01*
G01D02*
G03Y0I0J3937D01*
G01X297037Y-7874D02*
X301187D01*
G01D02*
G03Y0I0J3937D01*
G01X318510Y-7874D02*
X515333D01*
G01X318510Y0D02*
G03Y-7874I0J-3937D01*
G01D02*
X515333D01*
G01X318510Y0D02*
G03Y-7874I0J-3937D01*
G01X410610Y-445619D02*
X416069Y-463119D01*
X421528Y-445619D01*
G01X437936Y-463119D02*
X429202D01*
Y-445619D01*
X437936D01*
G01X434442Y-454077D02*
X429202D01*
G01X446702Y-463119D02*
Y-445619D01*
X452161D01*
X453907Y-446494D01*
X454999Y-447661D01*
X455436Y-449994D01*
X454999Y-452328D01*
X453689Y-453786D01*
X452161Y-454661D01*
X446702D01*
G01X452161D02*
X455436Y-463119D01*
G01X468569Y-463702D02*
X468132Y-463411D01*
Y-462827D01*
X468569Y-462536D01*
X469006Y-462827D01*
Y-463411D01*
X468569Y-463702D01*
G01X433569Y-508119D02*
Y-490619D01*
X430949Y-494119D01*
G01Y-508119D02*
X436189D01*
G01X452815Y-498786D02*
X453689Y-497911D01*
X454344Y-496453D01*
X454781Y-494410D01*
X454344Y-492661D01*
X453471Y-491494D01*
X451942Y-490619D01*
X446047D01*
Y-508119D01*
X453252D01*
X454781Y-506953D01*
X455654Y-505202D01*
X456091Y-503161D01*
X455654Y-501119D01*
X454344Y-499369D01*
X452815Y-498786D01*
X446047D01*
G01X515302Y-7874D02*
G03Y0I0J3937D01*
G01Y-7874D02*
G03Y0I0J3937D01*
G01X544152Y-445619D02*
Y-463119D01*
X552886D01*
G01X569949D02*
Y-451453D01*
G01Y-453494D02*
X569076Y-452328D01*
X567765Y-451744D01*
X566237Y-451453D01*
X564709Y-452036D01*
X563399Y-453202D01*
X562525Y-454952D01*
X562089Y-457286D01*
X562525Y-459619D01*
X563399Y-461369D01*
X564709Y-462536D01*
X566237Y-463119D01*
X567765Y-462827D01*
X569076Y-461953D01*
X569949Y-460786D01*
G01X578934Y-468369D02*
X580244Y-468952D01*
X581991Y-468369D01*
X583082Y-467203D01*
X583956Y-465744D01*
X585265Y-461078D01*
X588104Y-451453D01*
G01X581117D02*
X585265Y-461078D01*
G01X597744Y-455244D02*
X604731D01*
X604076Y-453202D01*
X602984Y-452036D01*
X601456Y-451453D01*
X599927Y-451744D01*
X598617Y-452619D01*
X597744Y-454661D01*
X597307Y-456411D01*
Y-458161D01*
X597744Y-459911D01*
X598836Y-461661D01*
X600146Y-462827D01*
X601674Y-463119D01*
X603202Y-462536D01*
X604731Y-460786D01*
G01X615462Y-463119D02*
Y-451453D01*
G01Y-453786D02*
X616554Y-452619D01*
X617646Y-451744D01*
X619174Y-451453D01*
X620265Y-451744D01*
X621576Y-452619D01*
G01X540499Y-7874D02*
X727049D01*
G01X540499Y0D02*
G03Y-7874I0J-3937D01*
G01D02*
X727049D01*
G01X540499Y0D02*
G03Y-7874I0J-3937D01*
G01X557269Y-490619D02*
Y-508119D01*
G01X552247Y-490619D02*
X562291D01*
G01X570184Y-505786D02*
X571931Y-507244D01*
X573896Y-508119D01*
X575642D01*
X577389Y-507244D01*
X578699Y-505786D01*
X579354Y-503744D01*
X578917Y-501703D01*
X577826Y-499952D01*
X575861Y-498786D01*
X573241Y-498202D01*
X571712Y-497036D01*
X571057Y-494994D01*
X571494Y-492952D01*
X572586Y-491494D01*
X574114Y-490619D01*
X575642D01*
X577171Y-491202D01*
X578481Y-492661D01*
G01X586592Y-508119D02*
Y-490619D01*
X592269Y-505202D01*
X597946Y-490619D01*
Y-508119D01*
G01X604966D02*
Y-490619D01*
X609332D01*
X611079Y-491494D01*
X612389Y-492661D01*
X613481Y-494410D01*
X614354Y-496453D01*
X614572Y-499369D01*
X614354Y-502286D01*
X613481Y-504328D01*
X612389Y-506078D01*
X611079Y-507244D01*
X609332Y-508119D01*
X604966D01*
G01X545472Y994290D02*
G03X552953I3740J1D01*
G01X545472D02*
Y1018109D01*
G01X552953D02*
Y994290D01*
G01X597047Y1018109D02*
Y1021653D01*
X595078Y1023622D01*
X554921D01*
X552952Y1021653D01*
X552953Y1018109D01*
G01X597047Y992126D02*
Y1018109D01*
G01X597048Y992126D02*
G03X600984Y988189I3937J0D01*
G01X713189D02*
X600984D01*
G01X641198Y996063D02*
X604922D01*
G01D02*
Y1023622D01*
G01X641198Y996063D02*
X604922D01*
G01D02*
Y1023622D01*
G01D02*
X709253D01*
G01X604922D02*
X709253D01*
G01X641198Y988189D02*
G03Y996063I0J3937D01*
G01Y988189D02*
G03Y996063I0J3937D01*
G01X649684Y1008622D02*
G03X658266I4291J0D01*
G01D02*
G03X649684I-4291J0D01*
G01X666395Y996063D02*
G03Y988189I0J-3937D01*
G01Y996063D02*
G03Y988189I0J-3937D01*
G01X709253Y996063D02*
X666395D01*
G01X709253D02*
X666395D01*
G01X686702Y-490619D02*
Y-508119D01*
X695436D01*
G01X703984Y-513369D02*
X705294Y-513952D01*
X707041Y-513369D01*
X708132Y-512203D01*
X709006Y-510744D01*
X710315Y-506078D01*
X713154Y-496453D01*
G01X706167D02*
X710315Y-506078D01*
G01X722357Y-508119D02*
Y-496453D01*
G01Y-499369D02*
X723231Y-497911D01*
X724541Y-496744D01*
X726287Y-496453D01*
X727815Y-496744D01*
X729126Y-497911D01*
X729781Y-499952D01*
Y-508119D01*
G01X739857D02*
Y-496453D01*
G01Y-499369D02*
X740731Y-497911D01*
X742041Y-496744D01*
X743787Y-496453D01*
X745315Y-496744D01*
X746626Y-497911D01*
X747281Y-499952D01*
Y-508119D01*
G01X774202Y-490619D02*
Y-508119D01*
X782936D01*
G01X796069Y-496453D02*
Y-508119D01*
G01Y-491786D02*
X795632Y-491494D01*
Y-490911D01*
X796069Y-490619D01*
X796506Y-490911D01*
Y-491494D01*
X796069Y-491786D01*
G01X809857Y-496453D02*
Y-504619D01*
X810731Y-506661D01*
X812041Y-507827D01*
X813569Y-508119D01*
X815097Y-507827D01*
X816407Y-506661D01*
X817281Y-504619D01*
G01Y-508119D02*
Y-496453D01*
G01X686266Y-463119D02*
Y-445619D01*
X690632D01*
X692379Y-446494D01*
X693689Y-447661D01*
X694781Y-449410D01*
X695654Y-451453D01*
X695872Y-454369D01*
X695654Y-457286D01*
X694781Y-459328D01*
X693689Y-461078D01*
X692379Y-462244D01*
X690632Y-463119D01*
X686266D01*
G01X705294Y-455244D02*
X712281D01*
X711626Y-453202D01*
X710534Y-452036D01*
X709006Y-451453D01*
X707477Y-451744D01*
X706167Y-452619D01*
X705294Y-454661D01*
X704857Y-456411D01*
Y-458161D01*
X705294Y-459911D01*
X706386Y-461661D01*
X707696Y-462827D01*
X709224Y-463119D01*
X710752Y-462536D01*
X712281Y-460786D01*
G01X722794Y-461078D02*
X723886Y-462244D01*
X725414Y-463119D01*
X726724D01*
X728034Y-462536D01*
X728907Y-461661D01*
X729344Y-460495D01*
X729126Y-458744D01*
X728252Y-457869D01*
X724322Y-456119D01*
X723449Y-454077D01*
X723886Y-452619D01*
X724759Y-451744D01*
X726069Y-451453D01*
X727379Y-451744D01*
X728689Y-452619D01*
G01X743569Y-451453D02*
Y-463119D01*
G01Y-446786D02*
X743132Y-446494D01*
Y-445911D01*
X743569Y-445619D01*
X744006Y-445911D01*
Y-446494D01*
X743569Y-446786D01*
G01X758012Y-467494D02*
X759541Y-468661D01*
X761287Y-468952D01*
X762815Y-468661D01*
X764126Y-467203D01*
X764999Y-465161D01*
Y-451453D01*
G01Y-453786D02*
X764126Y-452619D01*
X762815Y-451744D01*
X761287Y-451453D01*
X759541Y-452036D01*
X758449Y-453202D01*
X757575Y-455244D01*
X757139Y-457286D01*
X757357Y-459036D01*
X758231Y-461078D01*
X759541Y-462536D01*
X761287Y-463119D01*
X762597Y-462827D01*
X764126Y-461661D01*
X764999Y-460495D01*
G01X774857Y-463119D02*
Y-451453D01*
G01Y-454369D02*
X775731Y-452911D01*
X777041Y-451744D01*
X778787Y-451453D01*
X780315Y-451744D01*
X781626Y-452911D01*
X782281Y-454952D01*
Y-463119D01*
G01X792794Y-455244D02*
X799781D01*
X799126Y-453202D01*
X798034Y-452036D01*
X796506Y-451453D01*
X794977Y-451744D01*
X793667Y-452619D01*
X792794Y-454661D01*
X792357Y-456411D01*
Y-458161D01*
X792794Y-459911D01*
X793886Y-461661D01*
X795196Y-462827D01*
X796724Y-463119D01*
X798252Y-462536D01*
X799781Y-460786D01*
G01X810512Y-463119D02*
Y-451453D01*
G01Y-453786D02*
X811604Y-452619D01*
X812696Y-451744D01*
X814224Y-451453D01*
X815315Y-451744D01*
X816626Y-452619D01*
G01X713189Y988189D02*
G03X717126Y992126I0J3937D01*
G01Y1018109D02*
Y992126D01*
G01X709253Y1023622D02*
Y996063D01*
G01Y1023622D02*
Y996063D01*
G01X745472Y1018109D02*
Y1021653D01*
X743504Y1023622D01*
X719094D01*
X717126Y1021653D01*
Y1018109D01*
G01X727049Y-7874D02*
G03Y0I0J3937D01*
G01Y-7874D02*
G03Y0I0J3937D01*
G01X752246Y-7874D02*
X984201D01*
G01X752246Y0D02*
G03Y-7874I0J-3937D01*
G01D02*
X984201D01*
G01X752246Y0D02*
G03Y-7874I0J-3937D01*
G01X745472Y994290D02*
G03X752953I3741J1D01*
G01X745472D02*
Y1018109D01*
G01X752953D02*
Y994290D01*
G01X797047Y1018109D02*
Y1021653D01*
X795078Y1023622D01*
X754921D01*
X752952Y1021653D01*
X752953Y1018109D01*
G01X797047Y992126D02*
Y1018109D01*
G01X797048Y992126D02*
G03X800984Y988189I3937J0D01*
G01X902165D02*
X800984D01*
G01X859109Y996063D02*
X804922D01*
G01D02*
Y1023622D01*
G01X859109Y996063D02*
X804922D01*
G01D02*
Y1023622D01*
G01D02*
X1325399D01*
G01X804922D02*
X1325399D01*
G01X857269Y-508119D02*
Y-490619D01*
X854649Y-494119D01*
G01Y-508119D02*
X859889D01*
G01X874769D02*
Y-490619D01*
X872149Y-494119D01*
G01Y-508119D02*
X877389D01*
G01X888339Y-508702D02*
X896199Y-490619D01*
G01X909769Y-508119D02*
Y-490619D01*
X907149Y-494119D01*
G01Y-508119D02*
X912389D01*
G01X922466Y-504619D02*
X923775Y-506661D01*
X925522Y-507827D01*
X927487Y-508119D01*
X929234Y-507827D01*
X930981Y-506369D01*
X932072Y-504619D01*
X932291Y-502869D01*
X931854Y-500828D01*
X930326Y-499369D01*
X928797Y-498786D01*
X926832D01*
G01X928797D02*
X930107Y-497911D01*
X931199Y-496453D01*
X931636Y-494703D01*
X931199Y-492952D01*
X930107Y-491494D01*
X928142Y-490619D01*
X926177Y-490911D01*
X924212Y-492078D01*
G01X940839Y-508702D02*
X948699Y-490619D01*
G01X958121Y-493536D02*
X959431Y-491786D01*
X960959Y-490911D01*
X962706Y-490619D01*
X964889Y-491202D01*
X966417Y-492661D01*
X966854Y-494410D01*
X966636Y-496161D01*
X965762Y-497619D01*
X961396Y-500536D01*
X959431Y-502577D01*
X958121Y-505495D01*
X957684Y-508119D01*
X966854D01*
G01X979769Y-490619D02*
X978022Y-491202D01*
X976712Y-492661D01*
X975839Y-494410D01*
X975184Y-496744D01*
X974966Y-499369D01*
X975184Y-501994D01*
X975839Y-504328D01*
X976712Y-506078D01*
X978022Y-507536D01*
X979769Y-508119D01*
X981515Y-507536D01*
X982826Y-506078D01*
X983699Y-504328D01*
X984354Y-501994D01*
X984572Y-499369D01*
X984354Y-496744D01*
X983699Y-494410D01*
X982826Y-492661D01*
X981515Y-491202D01*
X979769Y-490619D01*
G01X997269Y-508119D02*
Y-490619D01*
X994649Y-494119D01*
G01Y-508119D02*
X999889D01*
G01X1017389D02*
Y-490619D01*
X1009310Y-503161D01*
X1020228D01*
G01X859109Y988189D02*
G03Y996063I0J3937D01*
G01Y988189D02*
G03Y996063I0J3937D01*
G01X884306D02*
G03Y988189I0J-3937D01*
G01Y996063D02*
G03Y988189I0J-3937D01*
G01X902166Y996063D02*
X884306D01*
G01X902166D02*
X884306D01*
G01X904966Y-463119D02*
Y-445619D01*
X909332D01*
X911079Y-446494D01*
X912389Y-447661D01*
X913481Y-449410D01*
X914354Y-451453D01*
X914572Y-454369D01*
X914354Y-457286D01*
X913481Y-459328D01*
X912389Y-461078D01*
X911079Y-462244D01*
X909332Y-463119D01*
X904966D01*
G01X931199D02*
Y-451453D01*
G01Y-453494D02*
X930326Y-452328D01*
X929015Y-451744D01*
X927487Y-451453D01*
X925959Y-452036D01*
X924649Y-453202D01*
X923775Y-454952D01*
X923339Y-457286D01*
X923775Y-459619D01*
X924649Y-461369D01*
X925959Y-462536D01*
X927487Y-463119D01*
X929015Y-462827D01*
X930326Y-461953D01*
X931199Y-460786D01*
G01X944769Y-445619D02*
Y-463119D01*
G01X941712Y-451453D02*
X947826D01*
G01X958994Y-455244D02*
X965981D01*
X965326Y-453202D01*
X964234Y-452036D01*
X962706Y-451453D01*
X961177Y-451744D01*
X959867Y-452619D01*
X958994Y-454661D01*
X958557Y-456411D01*
Y-458161D01*
X958994Y-459911D01*
X960086Y-461661D01*
X961396Y-462827D01*
X962924Y-463119D01*
X964452Y-462536D01*
X965981Y-460786D01*
G01X921850Y968503D02*
G03X902165Y988189I-19685J1D01*
G01X929725Y968504D02*
G03X902166Y996063I-27559J0D01*
G01D02*
X902195D01*
G01X929725Y968504D02*
G03X902166Y996063I-27559J0D01*
G01D02*
X902195D01*
G01X921850Y775590D02*
Y968503D01*
G01Y775590D02*
G03X925787Y771653I3937J0D01*
G01X984843D02*
X925787D01*
G01X929725Y779527D02*
Y886881D01*
G01Y779527D02*
X980906D01*
G01X929725D02*
Y886881D01*
G01Y779527D02*
X980906D01*
G01X929725Y886881D02*
G03X921851I-3937J1D01*
G01X929725D02*
G03X921851I-3937J1D01*
G01Y912079D02*
G03X929725I3937J-1D01*
G01X921851D02*
G03X929725I3937J-1D01*
G01Y912078D02*
Y968504D01*
G01Y912078D02*
Y968504D01*
G01X959606Y850829D02*
G03X951024I-4291J0D01*
G01D02*
G03X959606I4291J0D01*
G01X984201Y-7874D02*
G03Y0I0J3937D01*
G01Y-7874D02*
G03Y0I0J3937D01*
G01X984843Y771653D02*
G03X988780Y775590I0J3937D01*
G01X980907Y886881D02*
X980906Y779527D01*
G01X980907Y886881D02*
X980906Y779527D01*
G01X988781Y886881D02*
G03X980907I-3937J1D01*
G01X988781D02*
G03X980907I-3937J1D01*
G01Y912079D02*
G03X988781I3937J-1D01*
G01X980907D02*
G03X988781I3937J-1D01*
G01X980907D02*
X980906Y968504D01*
G01X980907Y912079D02*
X980906Y968504D01*
G01X1008465Y996063D02*
G03X980906Y968504I0J-27559D01*
G01X1008465Y996063D02*
G03X980906Y968504I0J-27559D01*
G01X988780Y968503D02*
Y775590D01*
G01X1008465Y988189D02*
G03X988780Y968503I0J-19685D01*
G01X1009398Y-7874D02*
X1108229D01*
G01X1009398Y0D02*
G03Y-7874I-1J-3937D01*
G01D02*
X1108229D01*
G01X1009398Y0D02*
G03Y-7874I-1J-3937D01*
G01X1380315Y988189D02*
X1008465D01*
G01X1070592Y996063D02*
X1008466D01*
G01X1070592D02*
X1008466D01*
G01X1070592Y988189D02*
G03Y996063I0J3937D01*
G01Y988189D02*
G03Y996063I0J3937D01*
G01X1095789D02*
G03Y988189I0J-3937D01*
G01Y996063D02*
G03Y988189I0J-3937D01*
G01X1325399Y996063D02*
X1095789D01*
G01X1325399D02*
X1095789D01*
G01X1112146Y3937D02*
Y210629D01*
G01X1108209Y0D02*
G03X1112146Y3937I0J3937D01*
G01X1108208Y-7874D02*
G03X1120020Y3938I1J11811D01*
G01X1108208Y-7874D02*
G03X1120020Y3938I1J11811D01*
G01Y99950D02*
G03X1112146I-3937J0D01*
G01X1120020D02*
G03X1112146I-3937J0D01*
G01Y125147D02*
G03X1120020I3937J0D01*
G01X1112146D02*
G03X1120020I3937J0D01*
G01X1116083Y214566D02*
X1194824D01*
G01X1116083D02*
G03X1112146Y210629I0J-3937D01*
G01X1120020Y99950D02*
Y3938D01*
G01Y99950D02*
Y3938D01*
G01Y125147D02*
Y206693D01*
G01Y125147D02*
Y206693D01*
G01X1120021D02*
X1190887D01*
G01X1120021D02*
X1190887D01*
G01X1161386Y128841D02*
G03X1152804I-4291J0D01*
G01D02*
G03X1161386I4291J0D01*
G01X1198760Y3937D02*
G03X1210571Y-7874I11811J0D01*
G01X1198760Y3937D02*
G03X1210571Y-7874I11811J0D01*
G01X1198761Y97100D02*
X1198760Y3937D01*
G01X1198761Y97100D02*
X1198760Y3937D01*
G01X1206635Y97100D02*
G03X1198761I-3937J0D01*
G01X1206635D02*
G03X1198761I-3937J0D01*
G01Y122297D02*
G03X1206635I3937J0D01*
G01X1198761D02*
G03X1206635I3937J0D01*
G01X1198761D02*
Y168002D01*
G01Y122297D02*
Y168002D01*
G01X1190887Y179134D02*
G03X1198761Y167998I11811J0D01*
G01X1190887Y179134D02*
G03X1198761Y167998I11811J0D01*
G01X1198760Y179133D02*
G03X1202697Y175196I3937J0D01*
G01X1198760Y210629D02*
Y179133D01*
G01X1190887Y206693D02*
Y179134D01*
G01Y206693D02*
Y179134D01*
G01X1198760Y210629D02*
G03X1194824Y214566I-3937J0D01*
G01X1210571Y0D02*
X1396063D01*
G01X1206634Y3937D02*
G03X1210571Y0I3937J0D01*
G01X1206634Y171259D02*
Y3937D01*
G01X1210552Y-7874D02*
X1210572D01*
G01D02*
G03Y0I0J3937D01*
G01X1210552Y-7874D02*
X1210572D01*
G01D02*
G03Y0I0J3937D01*
G01X1206634Y171259D02*
G03X1202697Y175196I-3937J0D01*
G01X1226320Y-7874D02*
X1380317D01*
G01X1226320Y0D02*
G03Y-7874I0J-3937D01*
G01D02*
X1380317D01*
G01X1226320Y0D02*
G03Y-7874I0J-3937D01*
G01X1354801Y996063D02*
X1325399D01*
G01X1354801D02*
X1325399D01*
G01Y1023622D02*
X1385001D01*
G01X1325399D02*
X1385001D01*
G01X1354801Y988189D02*
G03Y996063I0J3937D01*
G01Y988189D02*
G03Y996063I0J3937D01*
G01X1380316Y-7874D02*
G03Y0I0J3937D01*
G01Y-7874D02*
G03Y0I0J3937D01*
G01X1400000Y968503D02*
G03X1380315Y988189I-19685J1D01*
G01X1379998Y996063D02*
G03Y988189I0J-3937D01*
G01Y996063D02*
G03Y988189I0J-3937D01*
G01X1400001Y996063D02*
X1379998D01*
G01X1400001D02*
X1379998D01*
G01X1392127Y-25591D02*
G03X1400001Y-17717I0J7874D01*
G01X1392167Y-15015D02*
G03X1383585I-4291J0D01*
G01D02*
G03X1392167I4291J0D01*
G01X1392127Y-25591D02*
G03X1400001Y-17717I0J7874D01*
G01X1396063Y0D02*
G03X1400000Y3937I0J3937D01*
G01X1396064Y-7874D02*
X1400001D01*
G01X1396064Y0D02*
G03Y-7874I0J-3937D01*
G01D02*
X1400001D01*
G01X1396064Y0D02*
G03Y-7874I0J-3937D01*
G01X1380710Y1008622D02*
G03X1389292I4291J0D01*
G01D02*
G03X1380710I-4291J0D01*
G01X1400001D02*
G03X1385001Y1023622I-15000J0D01*
G01X1400001Y1008622D02*
G03X1385001Y1023622I-15000J0D01*
G01X1400001Y-17717D02*
Y-7874D01*
G01Y-17717D02*
Y-7874D01*
G01X1400000Y3937D02*
Y968503D01*
G01X1400001Y996063D02*
Y1008622D01*
G01Y996063D02*
Y1008622D01*
G54D42*
X152000Y465300D03*
X173943Y537396D03*
X197200Y431500D03*
X190200Y848000D03*
X317193Y450373D03*
X318223Y483783D03*
X333129Y241500D03*
X382700Y947000D03*
X469255Y301500D03*
Y305500D03*
X576700Y66000D03*
Y62000D03*
X628200Y575000D03*
X673786Y107874D03*
X686948Y122500D03*
X691162Y455464D03*
X709700Y568000D03*
X716200Y864000D03*
X771974Y475078D03*
X781700Y355500D03*
X796974Y475078D03*
X819200Y368500D03*
X817700Y849500D03*
X849200Y385000D03*
X846200Y638500D03*
X937650Y448700D03*
X1016700Y277500D03*
Y281500D03*
X1007700Y480500D03*
X1011916Y898468D03*
X1029700Y137000D03*
X1047200Y930000D03*
X1073629Y73758D03*
X1101700Y776500D03*
Y772500D03*
X1092668Y863284D03*
X1139700Y862000D03*
X1198668Y807784D03*
Y804284D03*
X1206700Y432500D03*
X1202200Y753000D03*
X1250200Y699500D03*
X1272200Y564500D03*
X1312817Y603912D03*
X1304700Y855000D03*
Y858500D03*
X1336700Y452000D03*
X1354200D03*
G54D51*
X196800Y905710D03*
Y913310D03*
X204900Y905710D03*
Y913310D03*
X267500Y204800D03*
Y197200D03*
X307485Y250672D03*
Y243072D03*
X324485Y251172D03*
Y243572D03*
X328429Y320300D03*
Y312700D03*
Y327200D03*
Y334800D03*
Y341700D03*
Y349300D03*
Y356200D03*
Y363800D03*
X318555Y436200D03*
X326555D03*
X318555Y443800D03*
X326555D03*
X336429Y320300D03*
Y312700D03*
Y327200D03*
Y334800D03*
Y341700D03*
Y349300D03*
Y356200D03*
Y363800D03*
X385500Y37600D03*
Y45200D03*
X579882Y269700D03*
Y277300D03*
X640500Y395700D03*
Y403300D03*
X648500Y395700D03*
Y403300D03*
X657000Y395700D03*
Y403300D03*
X692962Y450264D03*
Y442664D03*
X787000Y725200D03*
Y732800D03*
X802824Y336248D03*
Y343848D03*
X811838Y435740D03*
X820438D03*
X811838Y443340D03*
X820438D03*
X1028500Y254200D03*
X1036500D03*
X1028500Y261800D03*
X1036500D03*
X1045968Y172984D03*
Y180584D03*
X1066500Y173200D03*
Y180800D03*
X1084000Y148800D03*
Y141200D03*
X1083000Y173200D03*
X1072000Y165800D03*
Y158200D03*
X1080000Y165800D03*
Y158200D03*
X1074500Y173200D03*
X1083000Y180800D03*
X1074500D03*
X1085468Y882484D03*
Y890084D03*
X1088500Y753700D03*
Y761300D03*
X1103500Y787200D03*
Y794800D03*
X1093468Y882484D03*
Y890084D03*
X1114468Y248484D03*
Y256084D03*
X1128500Y825700D03*
Y833300D03*
X1141468Y876484D03*
X1149468D03*
X1141468Y884084D03*
X1149468D03*
X1157468Y876484D03*
X1165468D03*
X1157468Y884084D03*
X1165468D03*
X1257468Y466484D03*
Y474084D03*
X1277500Y462700D03*
Y470300D03*
X1293500Y446200D03*
Y453800D03*
Y462700D03*
X1285500D03*
X1293500Y470300D03*
X1285500D03*
X1302000Y462700D03*
Y470300D03*
X1366500Y429800D03*
Y422200D03*
X1374500Y429800D03*
Y422200D03*
G54D60*
X224297Y912750D03*
X230703D03*
G54D117*
X787758Y445022D03*
X785790D03*
Y457134D03*
X787758D03*
X1342984Y430444D03*
X1341016D03*
Y442556D03*
X1342984D03*
G54D135*
X1212840Y775850D03*
X1210280D03*
X1207720D03*
X1205160D03*
Y792150D03*
X1207720D03*
X1210280D03*
X1212840D03*
G54D126*
X1025473Y879350D03*
Y881909D03*
Y884468D03*
Y887027D03*
Y889586D03*
X1044959D03*
Y887027D03*
Y884468D03*
Y881909D03*
Y879350D03*
G54D144*
X1332967Y585538D03*
Y601286D03*
X1356267Y585538D03*
Y601286D03*
G54D108*
X737200Y56165D03*
Y63840D03*
Y61280D03*
Y58720D03*
X747800Y56165D03*
Y58720D03*
Y61280D03*
Y63840D03*
G54D15*
X26504Y845220D03*
Y849720D03*
X33504Y885720D03*
X58504Y830720D03*
X59504Y872720D03*
Y877720D03*
Y868220D03*
Y882220D03*
X78004Y885720D03*
X92504Y815220D03*
X104504Y844220D03*
X102504Y882720D03*
X119854Y316453D03*
Y320953D03*
X141700Y283500D03*
X139700Y312000D03*
X146700Y666500D03*
X141004Y791720D03*
Y783720D03*
X155500Y474300D03*
X176000Y457800D03*
X185255Y530000D03*
X193700Y840000D03*
Y844000D03*
Y856500D03*
X190200Y865500D03*
X194200Y878500D03*
X240700Y419000D03*
Y431000D03*
X246700Y835500D03*
X247200Y863500D03*
X264359Y425678D03*
Y430178D03*
Y434678D03*
X272700Y884500D03*
X324200Y93500D03*
X320723Y464283D03*
Y459783D03*
X320693Y454373D03*
X321723Y479783D03*
Y475283D03*
X316223Y507683D03*
X347200Y884500D03*
Y878500D03*
Y893000D03*
X354700Y884500D03*
Y878500D03*
Y893000D03*
Y889000D03*
X379255Y312500D03*
Y317000D03*
Y321500D03*
Y326000D03*
Y348500D03*
Y353000D03*
Y366500D03*
Y371000D03*
X364755Y385000D03*
Y376000D03*
Y380500D03*
Y371000D03*
X379255Y375500D03*
X365015Y400500D03*
X364755Y394000D03*
Y389500D03*
X378475Y403780D03*
X378505Y408500D03*
Y417500D03*
Y413000D03*
Y426500D03*
Y422000D03*
Y431000D03*
Y435500D03*
X380223Y387783D03*
X405700Y880500D03*
X424700Y268000D03*
X426455Y287200D03*
Y275200D03*
X442240Y106000D03*
Y110000D03*
X435240Y117500D03*
X442200Y244000D03*
X449700Y106000D03*
Y110000D03*
Y114500D03*
X461200Y277500D03*
Y273000D03*
X466129Y165500D03*
Y172500D03*
Y180500D03*
X465700Y197000D03*
X465629Y189500D03*
X465700Y286500D03*
X463200Y282000D03*
X472755Y293800D03*
X600200Y209500D03*
Y223000D03*
Y227500D03*
X639200Y453000D03*
X631700Y579000D03*
Y588500D03*
Y584000D03*
X631200Y606900D03*
Y612900D03*
X656164Y432538D03*
X648200Y444500D03*
X651700Y448500D03*
X677366Y94544D03*
X707700Y63500D03*
X694416Y137784D03*
X702200Y863500D03*
X713200Y576500D03*
Y582000D03*
Y572000D03*
X726232Y100532D03*
X734948Y189500D03*
X728200Y455500D03*
X739664Y558538D03*
Y563538D03*
X736168Y768784D03*
Y763984D03*
X729168Y806284D03*
Y801984D03*
X727700Y864000D03*
X757200Y82500D03*
Y88500D03*
Y94500D03*
Y99500D03*
X753164Y471538D03*
X741200Y553500D03*
X755700Y571000D03*
Y575500D03*
X743668Y768784D03*
X762200Y51500D03*
Y55500D03*
Y59500D03*
Y63500D03*
X766200Y138500D03*
Y134000D03*
X766100Y144300D03*
X779200Y649000D03*
X779700Y668000D03*
X800200Y471000D03*
X799200Y546500D03*
Y553500D03*
Y561000D03*
X805200Y851000D03*
X838700Y858000D03*
X824700Y873000D03*
X869200Y467500D03*
X860200Y711000D03*
X876200Y101500D03*
X873200Y414000D03*
Y404500D03*
X877200Y467500D03*
X920700Y70500D03*
X912200D03*
X986974Y204578D03*
Y209578D03*
Y214578D03*
X997700Y496500D03*
X1033200Y133000D03*
X1031474Y214078D03*
X1028416Y866968D03*
X1041200Y119500D03*
Y128500D03*
X1049200Y713000D03*
X1066168Y227284D03*
X1063668Y223284D03*
X1067700Y733500D03*
Y741500D03*
X1078668Y200784D03*
X1102700Y428000D03*
X1129200Y278000D03*
X1133200Y618000D03*
X1142200Y274500D03*
X1141200Y618000D03*
X1143168Y858284D03*
X1195877Y238000D03*
X1184700Y237000D03*
X1195877Y242500D03*
X1184700Y244000D03*
X1195877Y247500D03*
X1184700Y248000D03*
X1195877Y252500D03*
X1195868Y264060D03*
Y268560D03*
X1189700Y359000D03*
Y363500D03*
X1192200Y875500D03*
X1217200Y444000D03*
X1216670Y568510D03*
X1203700Y605500D03*
X1217984Y432532D03*
X1225700Y718500D03*
X1218200Y735500D03*
Y731000D03*
X1225700Y735500D03*
Y731000D03*
X1225200Y831500D03*
X1247700Y268500D03*
Y272500D03*
X1243700Y593000D03*
Y598000D03*
X1249200Y661000D03*
X1247700Y762000D03*
X1257188Y221500D03*
Y226000D03*
Y230500D03*
X1250877Y241500D03*
Y245500D03*
X1251700Y431500D03*
Y427500D03*
X1253700Y643000D03*
Y647000D03*
Y639000D03*
Y635000D03*
Y651000D03*
Y657000D03*
X1261200Y661000D03*
Y657000D03*
Y651000D03*
X1253700Y667000D03*
X1261200Y667500D03*
X1253700Y680000D03*
Y688000D03*
Y707500D03*
Y703500D03*
Y711500D03*
X1262700Y783000D03*
X1265300Y835100D03*
X1330700Y298000D03*
Y293000D03*
X1316317Y586412D03*
Y595412D03*
Y612412D03*
Y599912D03*
X1347317Y567412D03*
X1342317Y619412D03*
X1362200Y106000D03*
X1357700Y456000D03*
X1373317Y589912D03*
Y585412D03*
Y597912D03*
Y602412D03*
Y611412D03*
Y606912D03*
G54D24*
X39804Y931420D03*
X97500Y931200D03*
X153200Y660600D03*
X179000Y851700D03*
X180000Y906200D03*
X190000D03*
X185000D03*
X212500Y790700D03*
X343000Y67700D03*
X520000Y146200D03*
X687968Y760184D03*
X727968Y758184D03*
X793500Y727700D03*
X809000Y338200D03*
X810000Y474200D03*
X904500Y76200D03*
X1065500Y158700D03*
X1056700Y173200D03*
X1107968Y250984D03*
X1268468Y465984D03*
X1287000Y447200D03*
X1360000Y423700D03*
X1357500Y460700D03*
G54D33*
X97804Y803820D03*
X458000Y286500D03*
X547555Y364500D03*
X1197000Y366000D03*
X1219968Y790784D03*
X1312468Y902784D03*
G54D43*
X159555Y536250D03*
X163430Y543750D03*
X155680D03*
X764000Y653250D03*
X767875Y660750D03*
X760125D03*
X869987Y82376D03*
X866112Y89876D03*
X870625Y461750D03*
X873862Y89876D03*
X874500Y454250D03*
X878375Y461750D03*
X905625Y60750D03*
X909500Y53250D03*
X913375Y60750D03*
X1095500Y436750D03*
X1099375Y444250D03*
X1091625D03*
X1339000Y112250D03*
X1342875Y119750D03*
X1335125D03*
X1354000Y112250D03*
X1357875Y119750D03*
X1350125D03*
G54D52*
X214800Y823000D03*
X207200D03*
X244700Y841500D03*
X252300D03*
X274800Y188500D03*
X267200D03*
X274800Y180500D03*
X267200D03*
X314785Y227872D03*
X307185D03*
X314785Y235872D03*
X307185D03*
X313205Y319652D03*
X313129Y328500D03*
X313629Y342000D03*
X306729D03*
X299129D03*
X313629Y360500D03*
X322685Y235872D03*
X330285D03*
X322685Y227872D03*
X330285D03*
X320805Y319652D03*
X320729Y328500D03*
X321229Y342000D03*
Y360500D03*
X375200Y66000D03*
X367600D03*
X396700Y271400D03*
X405129Y251400D03*
X412729D03*
X404300Y271400D03*
X405129Y259400D03*
X412729D03*
X573300Y431500D03*
X565700D03*
X573300Y439500D03*
X565700D03*
X595598Y386616D03*
X603198D03*
X595598Y377616D03*
X603198D03*
X595598Y395116D03*
X603198D03*
X595598Y403616D03*
X603198D03*
X595598Y419616D03*
X603198D03*
X595598Y411616D03*
X603198D03*
X619700Y413000D03*
X627300D03*
X619700Y429000D03*
X627300D03*
X619700Y421000D03*
X627300D03*
X619700Y437000D03*
X627300D03*
X687966Y88544D03*
X680366D03*
X685186Y114964D03*
X677586D03*
X681662Y479464D03*
X689262D03*
X681662Y487464D03*
X689262D03*
X681662Y495464D03*
X689262D03*
X681700Y511500D03*
X689300D03*
X681662Y503464D03*
X689262D03*
X681700Y519500D03*
X689300D03*
X771574Y448078D03*
X763974D03*
X786300Y361500D03*
X778700D03*
X786300Y369500D03*
X778700D03*
X786300Y377500D03*
X778700D03*
X786300Y385500D03*
X778700D03*
X824300Y382000D03*
X816700D03*
X824300Y374000D03*
X816700D03*
X824300Y398000D03*
X816700D03*
X824300Y390000D03*
X816700D03*
X855300Y370000D03*
X847700D03*
X855300Y378500D03*
X847700D03*
X852300Y726500D03*
X844700D03*
X1000200Y69500D03*
X1007800D03*
X1052700Y858500D03*
Y850500D03*
Y874500D03*
Y866500D03*
X1045416Y906968D03*
X1053016D03*
X1045416Y914968D03*
X1053016D03*
X1060300Y858500D03*
Y850500D03*
Y874500D03*
Y866500D03*
X1257200Y570500D03*
X1264800D03*
X1298168Y434784D03*
X1305768D03*
X1325300Y427000D03*
X1317700D03*
X1364700Y380000D03*
Y388000D03*
X1372300Y380000D03*
Y388000D03*
G54D136*
X1233050Y778453D03*
Y772547D03*
X1248950Y778465D03*
Y772547D03*
G54D34*
X117654Y301703D03*
X113779Y309203D03*
X121529D03*
X139191Y298593D03*
X143066Y306093D03*
X135316D03*
G54D109*
X730940Y205035D03*
X733500D03*
X736060D03*
Y196965D03*
X733500D03*
X730940D03*
G54D118*
X774938Y685354D03*
X777498D03*
X780058D03*
Y692754D03*
X777498D03*
X774938D03*
X868936Y687711D03*
X871496D03*
Y695111D03*
X868936D03*
X874056Y687711D03*
Y695111D03*
X1064208Y201524D03*
X1066768D03*
Y208924D03*
X1064208D03*
X1069328Y201524D03*
Y208924D03*
G54D145*
X1333317Y587506D03*
Y589475D03*
Y591443D03*
Y593412D03*
Y595381D03*
Y597349D03*
Y599318D03*
X1355917Y597349D03*
Y595381D03*
Y593412D03*
Y591443D03*
Y589475D03*
Y587506D03*
Y599318D03*
G54D61*
X234614Y891272D03*
X236386D03*
G54D25*
X39804Y937020D03*
X97500Y936800D03*
X153200Y666200D03*
X179000Y857300D03*
X180000Y911800D03*
X190000D03*
X185000D03*
X212500Y796300D03*
X343000Y73300D03*
X520000Y151800D03*
X687968Y765784D03*
X727968Y763784D03*
X793500Y733300D03*
X809000Y343800D03*
X810000Y479800D03*
X904500Y81800D03*
X1065500Y164300D03*
X1056700Y178800D03*
X1107968Y256584D03*
X1268468Y471584D03*
X1287000Y452800D03*
X1360000Y429300D03*
X1357500Y466300D03*
G54D16*
X34304Y893920D03*
X29804D03*
X25304D03*
X38804D03*
Y901920D03*
X47804Y935920D03*
X58804Y717920D03*
X65804Y843420D03*
X76804Y717920D03*
X77804Y769920D03*
X73804D03*
X74304Y843420D03*
X83304D03*
X78804D03*
X99536Y762926D03*
X96772Y771204D03*
X92304Y843420D03*
X138000Y319700D03*
X134000Y674700D03*
Y682200D03*
X143500Y706200D03*
X153500Y674200D03*
Y682200D03*
X163000Y706200D03*
X168300Y453500D03*
X172800D03*
X187300D03*
X191800D03*
X195000Y887200D03*
X207500Y710700D03*
X212000D03*
X208000Y887200D03*
X216500Y710700D03*
X221000D03*
X236500Y832700D03*
X250000Y710700D03*
X265500Y901200D03*
X277500Y899200D03*
X296000Y91200D03*
X300500D03*
X305000D03*
X329055Y556200D03*
X333000Y97700D03*
X341000Y108740D03*
X347000Y108629D03*
X341000Y116240D03*
X346500Y914200D03*
X338000Y956200D03*
X342500D03*
X347000D03*
X353000Y84700D03*
X355055Y552700D03*
X355500Y914200D03*
X351000D03*
X359500D03*
X351500Y956200D03*
X356000D03*
X360500D03*
X375055Y467450D03*
X391055Y302700D03*
X380555Y467450D03*
X391555D03*
X386055D03*
X389000Y873700D03*
X393500D03*
X392000Y955200D03*
X420429Y261100D03*
X427555Y295200D03*
X433500Y239700D03*
X429429Y261100D03*
X444778Y812200D03*
X438278D03*
X444278Y875700D03*
X455000Y113200D03*
X459500D03*
X450778Y875700D03*
X475778Y812200D03*
X469278D03*
X473778Y875700D03*
X480278D03*
X544000Y154700D03*
X559000D03*
X554000D03*
X553055Y330700D03*
X557055D03*
X564000Y154700D03*
X585000Y256200D03*
X638876Y96914D03*
X656876D03*
X652376D03*
X647876D03*
X643376D03*
X655964Y444238D03*
X654962Y484164D03*
X674666Y90244D03*
X661376Y96914D03*
X668462Y484164D03*
X663962D03*
X682968Y773684D03*
Y765684D03*
X706716Y90484D03*
X700216Y151984D03*
X720032Y57416D03*
X724532Y65416D03*
X711216Y90484D03*
X720216D03*
X709216Y151984D03*
X713716D03*
X718216D03*
X722716D03*
X714000Y874700D03*
X740500Y82700D03*
X740748Y152200D03*
X727216Y151984D03*
X732500Y482200D03*
X745500Y152200D03*
X767000Y467200D03*
X760500Y484700D03*
X775748Y184200D03*
X779998Y676754D03*
X789500Y884700D03*
X798774Y437278D03*
X792500Y661700D03*
X802000Y731700D03*
X798000D03*
X822500Y407700D03*
X810000Y731700D03*
X829055Y273700D03*
X830500Y410700D03*
X867500Y624700D03*
Y617200D03*
X865468Y709984D03*
X875000Y444200D03*
X879500D03*
X880500Y478700D03*
X873500Y679700D03*
X953450Y441400D03*
X952450Y466900D03*
X957950Y441400D03*
X957068Y466950D03*
X1031000Y148700D03*
X1028716Y862168D03*
X1065688Y753304D03*
X1065838Y761244D03*
X1080468Y210984D03*
X1079688Y753434D03*
X1101500Y457700D03*
X1097000D03*
X1101468Y850484D03*
X1111000Y637700D03*
X1105968Y850484D03*
X1129000Y637700D03*
X1133000D03*
X1125000D03*
X1151500Y622700D03*
X1142000Y625700D03*
X1137000Y634700D03*
X1143218Y757064D03*
X1162468Y253484D03*
X1167500Y624200D03*
X1155500Y637700D03*
X1159500D03*
X1167500D03*
X1163500D03*
X1178000Y363700D03*
X1182000D03*
X1183000Y403700D03*
X1199000D03*
X1187000D03*
X1186500Y600700D03*
X1197000Y855200D03*
X1217000Y634200D03*
X1207000Y764700D03*
X1212500D03*
X1211000Y855200D03*
X1222500Y435700D03*
X1222000Y443700D03*
X1251000Y476200D03*
Y468700D03*
X1250600Y838800D03*
X1277000Y709200D03*
X1281000Y719700D03*
X1284500Y326700D03*
X1289468Y662984D03*
X1292968Y846984D03*
X1297468D03*
X1303784Y778732D03*
X1308784D03*
X1313784D03*
X1312500Y834200D03*
X1308500D03*
X1304500D03*
X1318500Y448700D03*
X1323117Y622112D03*
X1316500Y834200D03*
X1320500D03*
X1317500Y906200D03*
X1342000Y81200D03*
X1337468Y676484D03*
X1333468D03*
X1355000Y423700D03*
X1360617Y623112D03*
G54D127*
X1062000Y108750D03*
Y132250D03*
G54D70*
X304500Y125700D03*
Y137300D03*
X318000Y125700D03*
Y137300D03*
X579500Y369800D03*
Y358200D03*
X593000Y369800D03*
Y358200D03*
X778824Y334248D03*
X792324D03*
X778824Y345848D03*
X792324D03*
X1030000Y58700D03*
Y70300D03*
X1057000Y58700D03*
X1043500D03*
X1057000Y70300D03*
X1043500D03*
G54D26*
X43804Y932420D03*
X100772Y767704D03*
X85304Y884420D03*
X101804Y932420D03*
X216500Y431200D03*
X266500Y211200D03*
X270500D03*
X310429Y264200D03*
X328500Y94200D03*
X315429Y264200D03*
X320429D03*
X321023Y548483D03*
X325023D03*
X337000Y94200D03*
X333500Y946300D03*
X361929Y271200D03*
X352929D03*
X370929D03*
X375000D03*
X378929D03*
X674122Y126632D03*
X675055Y262700D03*
X679055D03*
X706055D03*
X710055D03*
X731468Y779684D03*
X727468D03*
X729468Y811184D03*
X725968D03*
X746716Y122984D03*
X750216D03*
X756000Y579700D03*
X788500Y658200D03*
X787500Y774700D03*
X791500D03*
X826500Y404200D03*
X854820Y344580D03*
X858500Y432700D03*
X880820Y348080D03*
X994500Y536700D03*
X1008500D03*
X1024716Y858668D03*
X1023716Y907668D03*
X1065500Y64200D03*
X1099500Y256200D03*
Y753200D03*
X1096000Y816200D03*
X1099468Y884484D03*
X1103000Y753200D03*
X1134500Y826910D03*
X1121968Y846984D03*
X1137748Y753484D03*
X1135468Y878984D03*
X1179677Y227700D03*
X1183177D03*
X1199677Y230200D03*
X1195677D03*
X1196500Y757700D03*
X1188000Y753700D03*
X1273000Y705700D03*
X1300784Y830732D03*
X1324500Y306200D03*
X1327500Y433200D03*
X1346617Y619612D03*
X1350617Y621112D03*
X1364617Y619612D03*
G54D119*
X789968Y743784D03*
Y763784D03*
X804968Y743784D03*
X799968D03*
X794968D03*
Y763784D03*
X799968D03*
X804968D03*
X870500Y720500D03*
X865500D03*
X860500D03*
Y740500D03*
X865500D03*
X870500D03*
X875500Y720500D03*
Y740500D03*
X1151468Y225784D03*
X1146468D03*
X1141468D03*
Y245784D03*
X1146468D03*
X1151468D03*
X1156468Y225784D03*
Y245784D03*
X1313784Y801032D03*
X1308784D03*
X1303784D03*
Y821032D03*
X1308784D03*
X1313784D03*
X1318784Y801032D03*
Y821032D03*
X1348084Y282757D03*
Y319907D03*
X1353084Y282757D03*
X1358084D03*
X1363084D03*
Y319907D03*
X1358084D03*
X1353084D03*
X1368084Y282757D03*
X1373084D03*
X1378084D03*
Y319907D03*
X1373084D03*
X1368084D03*
X1383084Y282757D03*
Y319907D03*
G54D80*
X332829Y248400D03*
X341029D03*
X332829Y262600D03*
X341029D03*
G54D137*
X1245921Y768500D03*
X1243953D03*
X1241984D03*
X1240016D03*
X1238047D03*
X1236079D03*
Y782500D03*
X1238047D03*
X1240016D03*
X1241984D03*
X1243953D03*
X1245921D03*
G54D146*
X1348084Y282053D03*
Y320611D03*
X1363084Y282053D03*
X1358084D03*
X1353084D03*
Y320611D03*
X1358084D03*
X1363084D03*
X1378084Y282053D03*
X1373084D03*
X1368084D03*
Y320611D03*
X1373084D03*
X1378084D03*
X1383084Y282053D03*
Y320611D03*
G54D71*
X311085Y217872D03*
X308885D03*
X311085Y221372D03*
X308885D03*
X303529Y336000D03*
X301329D03*
X303529Y332000D03*
X301329D03*
X341640Y132500D03*
X339440D03*
X341640Y130000D03*
X339440D03*
X341640Y136500D03*
X339440D03*
X341640Y139000D03*
X339440D03*
X341640Y143000D03*
X339440D03*
X341640Y145500D03*
X339440D03*
X341640Y152000D03*
X339440D03*
X341640Y149500D03*
X339440D03*
X341640Y169000D03*
X339440D03*
X341640Y171500D03*
X339440D03*
X341640Y165000D03*
X339440D03*
X341640Y156000D03*
X339440D03*
X341640Y162500D03*
X339440D03*
X341640Y158500D03*
X339440D03*
X341640Y175500D03*
X339440D03*
X341640Y178000D03*
X339440D03*
G54D53*
X215110Y848450D03*
Y868550D03*
X228890Y848450D03*
Y868550D03*
G54D62*
X235500Y887728D03*
G54D35*
X106654Y794785D03*
Y796750D03*
Y798720D03*
Y800690D03*
Y802655D03*
X122954Y794785D03*
Y802655D03*
Y800690D03*
Y798720D03*
Y796750D03*
X166700Y467345D03*
Y469315D03*
Y471285D03*
Y473255D03*
X175900Y467345D03*
Y473255D03*
Y471285D03*
Y469315D03*
X222673Y497608D03*
Y499578D03*
Y501543D03*
Y503513D03*
Y505483D03*
Y507453D03*
Y509418D03*
Y511388D03*
Y513358D03*
Y515323D03*
Y517293D03*
Y519263D03*
Y521228D03*
Y523198D03*
Y525168D03*
Y527138D03*
Y529103D03*
Y531073D03*
Y533043D03*
Y535008D03*
Y536978D03*
Y538948D03*
Y540913D03*
Y542883D03*
Y544853D03*
Y546823D03*
Y548788D03*
Y550758D03*
X298373Y499578D03*
Y497608D03*
Y515323D03*
Y513358D03*
Y511388D03*
Y509418D03*
Y507453D03*
Y505483D03*
Y503513D03*
Y501543D03*
Y533043D03*
Y531073D03*
Y529103D03*
Y527138D03*
Y525168D03*
Y523198D03*
Y521228D03*
Y519263D03*
Y517293D03*
Y548788D03*
Y546823D03*
Y544853D03*
Y542883D03*
Y540913D03*
Y538948D03*
Y536978D03*
Y535008D03*
Y550758D03*
X871420Y348835D03*
Y346865D03*
Y344895D03*
Y342925D03*
X862220D03*
Y344895D03*
Y346865D03*
Y348835D03*
X950850Y447745D03*
Y449715D03*
Y451685D03*
Y453655D03*
X960050Y449715D03*
Y447745D03*
Y453655D03*
Y451685D03*
X1110318Y263849D03*
Y265814D03*
Y267784D03*
Y269754D03*
Y271719D03*
X1126618Y269754D03*
Y267784D03*
Y265814D03*
Y263849D03*
Y271719D03*
X1288818Y641849D03*
Y643814D03*
Y645784D03*
Y647754D03*
Y649719D03*
X1288318Y673349D03*
Y675314D03*
Y677284D03*
Y679254D03*
Y681219D03*
X1305118Y647754D03*
Y645784D03*
Y643814D03*
Y641849D03*
Y649719D03*
X1304618Y679254D03*
Y677284D03*
Y675314D03*
Y673349D03*
Y681219D03*
G54D44*
X166200Y666500D03*
X310100Y56700D03*
Y51700D03*
Y61700D03*
X380200Y943000D03*
X432255Y290600D03*
X682700Y473000D03*
X759948Y123500D03*
X787974Y434078D03*
X784200Y897000D03*
X806474Y465078D03*
X876200Y330000D03*
X1050916Y277968D03*
X1050700Y283000D03*
X1067700Y141000D03*
X1079200Y412000D03*
X1091700Y61000D03*
Y66500D03*
X1110700Y280000D03*
X1140168Y252784D03*
X1145200Y592500D03*
X1146700Y827000D03*
X1181270Y777000D03*
X1222200Y452500D03*
X1248400Y209700D03*
X1249200Y675500D03*
X1276200Y569000D03*
X1286112Y434712D03*
X1304200Y363000D03*
X1344700Y420000D03*
X1348317Y562412D03*
G54D17*
X34304Y890520D03*
X29804D03*
X25304D03*
X38804D03*
Y898520D03*
X47804Y932520D03*
X58804Y714520D03*
X65804Y840020D03*
X76804Y714520D03*
X77804Y766520D03*
X73804D03*
X74304Y840020D03*
X83304D03*
X78804D03*
X99536Y759526D03*
X96772Y767804D03*
X92304Y840020D03*
X138000Y316300D03*
X134000Y678800D03*
Y671300D03*
X143500Y702800D03*
X153500Y678800D03*
Y670800D03*
X163000Y702800D03*
X168300Y450100D03*
X172800D03*
X187300D03*
X191800D03*
X195000Y883800D03*
X207500Y707300D03*
X212000D03*
X208000Y883800D03*
X216500Y707300D03*
X221000D03*
X236500Y829300D03*
X250000Y707300D03*
X265500Y897800D03*
X277500Y895800D03*
X296000Y87800D03*
X300500D03*
X305000D03*
X329055Y552800D03*
X341000Y105340D03*
X347000Y105229D03*
X333000Y94300D03*
X341000Y112840D03*
X346500Y910800D03*
X338000Y952800D03*
X342500D03*
X347000D03*
X353000Y81300D03*
X355055Y549300D03*
X355500Y910800D03*
X351000D03*
X359500D03*
X351500Y952800D03*
X356000D03*
X360500D03*
X375055Y464050D03*
X391055Y299300D03*
X380555Y464050D03*
X391555D03*
X386055D03*
X389000Y870300D03*
X393500D03*
X392000Y951800D03*
X420429Y257700D03*
X427555Y291800D03*
X433500Y236300D03*
X429429Y257700D03*
X444778Y808800D03*
X438278D03*
X444278Y872300D03*
X455000Y109800D03*
X459500D03*
X450778Y872300D03*
X475778Y808800D03*
X469278D03*
X473778Y872300D03*
X480278D03*
X544000Y151300D03*
X559000D03*
X554000D03*
X553055Y327300D03*
X557055D03*
X564000Y151300D03*
X585000Y252800D03*
X638876Y93514D03*
X656876D03*
X652376D03*
X647876D03*
X643376D03*
X655964Y440838D03*
X654962Y480764D03*
X674666Y86844D03*
X661376Y93514D03*
X668462Y480764D03*
X663962D03*
X682968Y762284D03*
Y770284D03*
X706716Y87084D03*
X700216Y148584D03*
X720032Y54016D03*
X724532Y62016D03*
X711216Y87084D03*
X720216D03*
X709216Y148584D03*
X713716D03*
X718216D03*
X722716D03*
X714000Y871300D03*
X740500Y79300D03*
X740748Y148800D03*
X727216Y148584D03*
X732500Y478800D03*
X745500Y148800D03*
X767000Y463800D03*
X760500Y481300D03*
X775748Y180800D03*
X779998Y673354D03*
X789500Y881300D03*
X798774Y433878D03*
X792500Y658300D03*
X802000Y728300D03*
X798000D03*
X822500Y404300D03*
X810000Y728300D03*
X829055Y270300D03*
X830500Y407300D03*
X867500Y613800D03*
Y621300D03*
X865468Y706584D03*
X875000Y440800D03*
X879500D03*
X880500Y475300D03*
X873500Y676300D03*
X953450Y438000D03*
X952450Y463500D03*
X957950Y438000D03*
X957068Y463550D03*
X1031000Y145300D03*
X1028716Y858768D03*
X1065688Y749904D03*
X1065838Y757844D03*
X1080468Y207584D03*
X1079688Y750034D03*
X1101500Y454300D03*
X1097000D03*
X1101468Y847084D03*
X1111000Y634300D03*
X1105968Y847084D03*
X1129000Y634300D03*
X1133000D03*
X1125000D03*
X1151500Y619300D03*
X1137000Y631300D03*
X1142000Y622300D03*
X1143218Y753664D03*
X1162468Y250084D03*
X1167500Y620800D03*
X1155500Y634300D03*
X1159500D03*
X1167500D03*
X1163500D03*
X1178000Y360300D03*
X1182000D03*
X1183000Y400300D03*
X1199000D03*
X1187000D03*
X1186500Y597300D03*
X1197000Y851800D03*
X1217000Y630800D03*
X1207000Y761300D03*
X1212500D03*
X1211000Y851800D03*
X1222500Y432300D03*
X1222000Y440300D03*
X1251000Y465300D03*
Y472800D03*
X1250600Y835400D03*
X1277000Y705800D03*
X1281000Y716300D03*
X1284500Y323300D03*
X1289468Y659584D03*
X1292968Y843584D03*
X1297468D03*
X1303784Y775332D03*
X1308784D03*
X1313784D03*
X1312500Y830800D03*
X1308500D03*
X1304500D03*
X1318500Y445300D03*
X1323117Y618712D03*
X1316500Y830800D03*
X1320500D03*
X1317500Y902800D03*
X1342000Y77800D03*
X1337468Y673084D03*
X1333468D03*
X1355000Y420300D03*
X1360617Y619712D03*
G54D128*
X1077000Y238000D03*
Y260000D03*
G54D36*
X127654Y303753D03*
X190500Y889800D03*
X212500Y807300D03*
X203500Y889800D03*
X220500D03*
X274000Y915800D03*
X269000D03*
X295500Y130300D03*
X306400Y75200D03*
X301400D03*
X302159Y430478D03*
X332500Y941400D03*
X348000Y87300D03*
X353000Y76800D03*
X348000Y76300D03*
X392000Y45300D03*
X659462Y495264D03*
X687968Y776784D03*
X727968Y774784D03*
X784274Y481378D03*
X775500Y710800D03*
X806274Y459878D03*
X1018500Y501800D03*
X1026500Y147300D03*
X1052100Y182400D03*
X1095000Y757800D03*
X1175177Y231800D03*
X1190500Y233300D03*
X1263700Y473000D03*
X1324000Y55800D03*
X1347000Y83800D03*
X1343000Y461800D03*
X1362500Y443800D03*
Y454800D03*
G54D27*
X43804Y936020D03*
X100772Y771304D03*
X85304Y888020D03*
X101804Y936020D03*
X216500Y434800D03*
X266500Y214800D03*
X270500D03*
X310429Y267800D03*
X328500Y97800D03*
X315429Y267800D03*
X320429D03*
X321023Y552083D03*
X325023D03*
X337000Y97800D03*
X333500Y949900D03*
X361929Y274800D03*
X352929D03*
X370929D03*
X375000D03*
X378929D03*
X674122Y130232D03*
X675055Y266300D03*
X679055D03*
X706055D03*
X710055D03*
X731468Y783284D03*
X727468D03*
X729468Y814784D03*
X725968D03*
X746716Y126584D03*
X750216D03*
X756000Y583300D03*
X788500Y661800D03*
X787500Y778300D03*
X791500D03*
X826500Y407800D03*
X854820Y348180D03*
X858500Y436300D03*
X880820Y351680D03*
X994500Y540300D03*
X1008500D03*
X1024716Y862268D03*
X1023716Y911268D03*
X1065500Y67800D03*
X1099500Y259800D03*
Y756800D03*
X1096000Y819800D03*
X1099468Y888084D03*
X1103000Y756800D03*
X1134500Y830510D03*
X1121968Y850584D03*
X1137748Y757084D03*
X1135468Y882584D03*
X1179677Y231300D03*
X1183177D03*
X1199677Y233800D03*
X1195677D03*
X1196500Y761300D03*
X1188000Y757300D03*
X1273000Y709300D03*
X1300784Y834332D03*
X1324500Y309800D03*
X1327500Y436800D03*
X1346617Y623212D03*
X1350617Y624712D03*
X1364617Y623212D03*
G54D90*
X479923Y298683D03*
Y306883D03*
X494123Y298683D03*
Y306883D03*
G54D72*
X330200Y9000D03*
Y20000D03*
X347600Y9000D03*
X338900D03*
X347600Y20000D03*
X338900D03*
X356300Y9000D03*
X365000D03*
X356300Y20000D03*
X365000D03*
X359000Y34000D03*
Y45000D03*
X377000Y34000D03*
X368000D03*
X377000Y45000D03*
X368000D03*
X1047500Y831500D03*
Y842500D03*
X1075500Y893500D03*
Y882500D03*
X1180500Y826000D03*
Y837000D03*
X1374500Y438500D03*
Y449500D03*
G54D147*
X1348595Y545800D03*
X1342639D03*
X1348595Y555024D03*
X1342639D03*
G54D63*
X244000Y894000D03*
X249000D03*
X254000D03*
X259000D03*
X1050000Y260000D03*
X1045000D03*
X1060000D03*
X1055000D03*
G54D54*
X211950Y851610D03*
Y865390D03*
X232050Y851610D03*
Y865390D03*
G54D18*
X48820Y403503D03*
X45670D03*
X42520D03*
X39370D03*
X50395Y393623D03*
X47245D03*
X44095D03*
X40945D03*
X67715Y403503D03*
X64565D03*
X61415D03*
X58270D03*
X55120D03*
X66140Y393623D03*
X62990D03*
X59840D03*
X56695D03*
X53545D03*
X51970Y403503D03*
X77165D03*
X74015D03*
X70865D03*
X78740Y393623D03*
X75590D03*
X72440D03*
X69290D03*
X166141Y303465D03*
X162992D03*
X164567Y313347D03*
X161417D03*
X181889Y303465D03*
X178740D03*
X175590D03*
X172441D03*
X169291D03*
X180315Y313347D03*
X177165D03*
X174015D03*
X170866D03*
X167716D03*
X197637Y303465D03*
X194488D03*
X191338D03*
X188189D03*
X185039D03*
X196063Y313347D03*
X192913D03*
X189763D03*
X186614D03*
X183464D03*
X213385Y303465D03*
X210236D03*
X207086D03*
X203937D03*
X200787D03*
X214960Y313347D03*
X211811D03*
X208661D03*
X205511D03*
X202362D03*
X199212D03*
X216535Y303465D03*
G54D45*
X175993Y544096D03*
X179743D03*
Y554696D03*
X175993D03*
X183493Y544096D03*
Y554696D03*
X1094250Y90300D03*
X1090500D03*
X1086750D03*
Y79700D03*
X1090500D03*
X1094250D03*
G54D129*
X1081260Y418200D03*
X1085000Y426800D03*
X1088740Y418200D03*
G54D81*
X342429Y316600D03*
Y314400D03*
X346429Y316600D03*
Y314400D03*
X516283Y318377D03*
X519283D03*
X516283Y320577D03*
X519283D03*
G54D138*
X1241000Y775500D03*
G54D139*
X1275984Y17914D03*
X1295670D03*
X1285827D03*
G54D19*
X48820Y422933D03*
X67717D03*
X58268D03*
G54D73*
X331130Y72321D03*
Y68384D03*
X320714Y70353D03*
G54D46*
X181055Y565550D03*
X178496D03*
X181055Y573450D03*
X178496D03*
X183614Y565550D03*
Y573450D03*
X390988Y248050D03*
X388429D03*
X385870D03*
X390988Y255950D03*
X388429D03*
X385870D03*
G54D91*
X543699Y168150D03*
X541729D03*
X539759D03*
X537789D03*
X535824D03*
X533854D03*
Y243850D03*
X535824D03*
X537789D03*
X539759D03*
X541729D03*
X543699D03*
X559444Y168150D03*
X557474D03*
X555509D03*
X553539D03*
X551569D03*
X549604D03*
X547634D03*
X545664D03*
Y243850D03*
X547634D03*
X549604D03*
X551569D03*
X553539D03*
X555509D03*
X557474D03*
X559444D03*
X575194Y168150D03*
X573224D03*
X571254D03*
X569289D03*
X567319D03*
X565349D03*
X563384D03*
X561414D03*
Y243850D03*
X563384D03*
X565349D03*
X567319D03*
X569289D03*
X571254D03*
X573224D03*
X575194D03*
X587004Y168150D03*
X585034D03*
X583069D03*
X581099D03*
X579129D03*
X577159D03*
Y243850D03*
X579129D03*
X581099D03*
X583069D03*
X585034D03*
X587004D03*
X1311403Y874634D03*
X1309438D03*
X1307468D03*
X1305498D03*
X1303533D03*
Y890934D03*
X1305498D03*
X1307468D03*
X1309438D03*
X1311403D03*
X1331438Y643634D03*
X1329468D03*
X1327498D03*
X1325533D03*
Y659934D03*
X1327498D03*
X1329468D03*
X1331438D03*
X1333403Y643634D03*
Y659934D03*
G54D148*
X1336743Y581762D03*
Y605062D03*
X1352491Y581762D03*
Y605062D03*
G54D55*
X212250Y853579D03*
Y855547D03*
Y857516D03*
Y859484D03*
Y861453D03*
Y863421D03*
X231750Y859484D03*
Y857516D03*
Y855547D03*
Y853579D03*
Y863421D03*
Y861453D03*
G54D64*
X271500Y893500D03*
Y902500D03*
G54D28*
X59787Y669714D03*
X61362D03*
X62937D03*
X64512D03*
X66087D03*
Y691914D03*
X64512D03*
X62937D03*
X61362D03*
X59787D03*
X67662Y669714D03*
X69232D03*
X70807D03*
X72382D03*
X73957D03*
X75532D03*
X77107D03*
Y691914D03*
X75532D03*
X73957D03*
X72382D03*
X70807D03*
X69232D03*
X67662D03*
X94587Y669714D03*
X96162D03*
X97737D03*
X99312D03*
Y691914D03*
X97737D03*
X96162D03*
X94587D03*
X100887Y669714D03*
X102462D03*
X104032D03*
X105607D03*
X107182D03*
X108757D03*
X110332D03*
X111907D03*
Y691914D03*
X110332D03*
X108757D03*
X107182D03*
X105607D03*
X104032D03*
X102462D03*
X100887D03*
X323395Y517900D03*
X324970D03*
X326545D03*
X328120D03*
X329695D03*
Y540100D03*
X328120D03*
X326545D03*
X324970D03*
X323395D03*
X331270Y517900D03*
X332840D03*
X334415D03*
X335990D03*
X337565D03*
X339140D03*
X340715D03*
Y540100D03*
X339140D03*
X337565D03*
X335990D03*
X334415D03*
X332840D03*
X331270D03*
X347738Y517994D03*
X349313D03*
X350888D03*
X352463D03*
X354038D03*
X355613D03*
X357183D03*
X358758D03*
X360333D03*
X361908D03*
Y540194D03*
X360333D03*
X358758D03*
X357183D03*
X355613D03*
X354038D03*
X352463D03*
X350888D03*
X349313D03*
X347738D03*
X363483Y517994D03*
X365058D03*
Y540194D03*
X363483D03*
G54D82*
X364700Y55500D03*
X376300D03*
X576300Y380500D03*
X564700D03*
X576300Y394000D03*
X564700D03*
X576300Y421000D03*
X564700D03*
X576300Y407500D03*
X564700D03*
X886200Y70500D03*
Y84500D03*
X897800Y70500D03*
Y84500D03*
X1247700Y176000D03*
Y189000D03*
X1259300Y176000D03*
Y189000D03*
G54D37*
X127654Y298153D03*
X190500Y884200D03*
X212500Y801700D03*
X203500Y884200D03*
X220500D03*
X274000Y910200D03*
X269000D03*
X295500Y124700D03*
X306400Y69600D03*
X301400D03*
X302159Y424878D03*
X332500Y935800D03*
X353000Y71200D03*
X348000Y70700D03*
Y81700D03*
X392000Y39700D03*
X659462Y489664D03*
X687968Y771184D03*
X727968Y769184D03*
X784274Y475778D03*
X775500Y705200D03*
X806274Y454278D03*
X1018500Y496200D03*
X1026500Y141700D03*
X1052100Y176800D03*
X1095000Y752200D03*
X1175177Y226200D03*
X1190500Y227700D03*
X1263700Y467400D03*
X1324000Y50200D03*
X1347000Y78200D03*
X1343000Y456200D03*
X1362500Y438200D03*
Y449200D03*
G54D29*
X63304Y714520D03*
X55304Y750520D03*
X63272Y794304D03*
X58772D03*
X67772D03*
X81304Y714520D03*
X69804Y840020D03*
X96772Y714304D03*
X92772D03*
X87804Y840020D03*
X103804Y759520D03*
X102304Y887020D03*
X127654Y308753D03*
X179500Y862300D03*
X189555Y566800D03*
X194500Y861300D03*
X199000Y883800D03*
X210000Y829300D03*
X212000Y883800D03*
X232000Y829300D03*
X228000D03*
X220000D03*
X224000D03*
X216000Y883800D03*
X225000Y887300D03*
X229500D03*
X234623Y565983D03*
X273500Y197800D03*
X313485Y245172D03*
X312555Y439300D03*
X317985Y245172D03*
X341000Y94300D03*
X347000Y112729D03*
X357429Y246800D03*
X361929D03*
X352929D03*
X361178Y982300D03*
X366429Y246800D03*
X375429D03*
X370929D03*
X379929D03*
X376000Y869800D03*
X371500D03*
X380000Y918800D03*
X375500D03*
X373678Y982300D03*
X386555Y299300D03*
X395555D03*
X384500Y870300D03*
X384000Y918800D03*
X396929Y253800D03*
X412500Y265300D03*
X400555Y299300D03*
X405555D03*
X409555D03*
X398000Y870300D03*
X424929Y249700D03*
X420429D03*
X424929Y257700D03*
X423055Y293800D03*
X418555Y299300D03*
X414055D03*
X434540Y106300D03*
X440000Y236300D03*
X433929Y257700D03*
X444778Y805300D03*
X438278D03*
X444278Y875800D03*
X458555Y293300D03*
X450778Y875800D03*
X475778Y805300D03*
X469278D03*
X473778Y875800D03*
X480278D03*
X549000Y151300D03*
X549055Y327300D03*
X558955Y368200D03*
X554955D03*
X571000Y151300D03*
X659462Y480764D03*
X682382Y122742D03*
X678222Y122892D03*
X686432Y126312D03*
X690512Y126252D03*
X704716Y148584D03*
X698968Y779284D03*
X704000Y884800D03*
X724532Y54016D03*
X720032Y62016D03*
X715716Y87084D03*
X715468Y754784D03*
X736248Y148800D03*
X731716Y148584D03*
X725748Y180800D03*
X726000Y891300D03*
X763000Y455800D03*
X767000D03*
Y471800D03*
X765998Y707854D03*
X770498D03*
X788774Y475378D03*
X779774D03*
X780500Y881300D03*
X785000D03*
X806000Y728300D03*
X838055Y270300D03*
X833555D03*
X847055D03*
X851555D03*
X856055D03*
X842555D03*
X866500Y100800D03*
X865055Y270300D03*
X860555D03*
X868820Y356680D03*
X863820D03*
X867000Y432800D03*
X862500D03*
X869468Y701584D03*
X879500Y87800D03*
X873468Y701584D03*
X919000Y51800D03*
X998000Y480800D03*
X1003000D03*
X999000Y536800D03*
X1003000D03*
X1010500Y451800D03*
X1011000Y496800D03*
X1017000Y536800D03*
X1013000D03*
X1029500Y120800D03*
X1025500Y133300D03*
X1035000Y175300D03*
X1027716Y907768D03*
X1032216D03*
X1039500Y175300D03*
X1070478Y750024D03*
X1074968Y749984D03*
X1070098Y757884D03*
X1093961Y99842D03*
X1089961D03*
X1089500Y408800D03*
X1088000Y454300D03*
X1092500D03*
X1087988Y741924D03*
X1101968Y806584D03*
X1117500Y614300D03*
X1103000Y634300D03*
X1107000D03*
X1115000D03*
X1111000Y742300D03*
X1107468Y806384D03*
X1106500Y833800D03*
X1122000Y614300D03*
X1149934Y581472D03*
X1137500Y622300D03*
X1151500Y626800D03*
X1146500Y622300D03*
X1146000Y634300D03*
X1151500D03*
X1135468Y858584D03*
X1159500Y620300D03*
X1179000Y400300D03*
X1172000Y753800D03*
X1180000D03*
X1184000D03*
X1176000D03*
X1191000Y400300D03*
X1195000D03*
X1189000Y742300D03*
X1192000Y753800D03*
X1213000Y630800D03*
X1209000D03*
X1205000D03*
X1201000D03*
X1201968Y761084D03*
X1215716Y805768D03*
X1211216D03*
X1207000Y805800D03*
X1215500Y851800D03*
X1201500D03*
X1226500Y440300D03*
X1225500Y789800D03*
X1220000Y805800D03*
X1246500Y465300D03*
X1242000D03*
X1238100Y853900D03*
X1257000Y36300D03*
X1271500Y545300D03*
X1276000Y660300D03*
X1281000Y705800D03*
X1277000Y716300D03*
X1295500Y30800D03*
X1284500Y314800D03*
X1293968Y659584D03*
X1285000Y659800D03*
X1310500Y39800D03*
X1314500D03*
X1299968Y658084D03*
X1303784Y785832D03*
X1308784D03*
X1314284D03*
X1312500Y854050D03*
X1307468Y913584D03*
X1301968D03*
X1312468D03*
X1327000Y328800D03*
X1323500Y433300D03*
Y445300D03*
X1332117Y618712D03*
X1327617D03*
X1328968Y673084D03*
X1326000Y854050D03*
X1317000D03*
X1321500D03*
X1316968Y913584D03*
X1332500Y50800D03*
X1336500Y135300D03*
X1338500Y456300D03*
X1347468Y453084D03*
X1352000Y78300D03*
X1363117Y562212D03*
X1354417Y619712D03*
G54D56*
X214400Y912820D03*
Y898980D03*
G54D92*
X629000Y333600D03*
Y358400D03*
X649500Y333600D03*
Y358400D03*
G54D47*
X181055Y569500D03*
X388429Y252000D03*
G54D65*
X299474Y111000D03*
X332526D03*
G54D38*
X129600Y839160D03*
Y841720D03*
Y844280D03*
Y846840D03*
X142400Y844280D03*
Y841720D03*
Y839160D03*
Y846840D03*
X331623Y454943D03*
Y457503D03*
Y460063D03*
Y462623D03*
X331123Y476943D03*
Y479503D03*
Y482063D03*
Y484623D03*
X344423Y462623D03*
Y460063D03*
Y457503D03*
Y454943D03*
X343923Y482063D03*
Y479503D03*
Y476943D03*
Y484623D03*
X368900Y882420D03*
Y884980D03*
Y887540D03*
Y890100D03*
Y892660D03*
Y895220D03*
Y897780D03*
Y900340D03*
Y902900D03*
Y905460D03*
Y908020D03*
Y910580D03*
X391100Y892660D03*
Y890100D03*
Y887540D03*
Y884980D03*
Y882420D03*
Y910580D03*
Y908020D03*
Y905460D03*
Y902900D03*
Y900340D03*
Y897780D03*
Y895220D03*
X433765Y276060D03*
Y278620D03*
Y281180D03*
Y283740D03*
X449945D03*
Y281180D03*
Y278620D03*
Y276060D03*
X639874Y577738D03*
Y580298D03*
Y582858D03*
Y585418D03*
X652674Y580298D03*
Y577738D03*
Y585418D03*
Y582858D03*
X723600Y573160D03*
Y575720D03*
Y578280D03*
Y580840D03*
X736400D03*
Y578280D03*
Y575720D03*
Y573160D03*
X745400Y894120D03*
Y891560D03*
Y889000D03*
Y886440D03*
Y883880D03*
Y881325D03*
Y896675D03*
X765694Y573128D03*
Y575688D03*
Y578248D03*
Y580808D03*
X767600Y881325D03*
Y883880D03*
Y886440D03*
Y889000D03*
Y891560D03*
Y894120D03*
Y896675D03*
X778494Y580808D03*
Y578248D03*
Y575688D03*
Y573128D03*
G54D149*
X1346586Y582112D03*
X1344617D03*
X1342648D03*
X1340680D03*
X1338711D03*
Y604712D03*
X1340680D03*
X1342648D03*
X1344617D03*
X1346586D03*
X1350523Y582112D03*
X1348554D03*
Y604712D03*
X1350523D03*
G54D83*
X360433Y131496D03*
Y134645D03*
X357284D03*
X360433Y137795D03*
X357284D03*
X360433Y216535D03*
X357284D03*
X360433Y219685D03*
X357284D03*
X360433Y222834D03*
X363583Y131496D03*
Y134645D03*
Y137795D03*
Y216535D03*
Y219685D03*
Y222834D03*
X442323Y131496D03*
Y134645D03*
Y137795D03*
Y216535D03*
Y219685D03*
Y222834D03*
X445473Y131496D03*
X448622Y134645D03*
X445473D03*
X448622Y137795D03*
X445473D03*
X448622Y216535D03*
X445473D03*
X448622Y219685D03*
X445473D03*
Y222834D03*
X1121397Y662363D03*
X1124547D03*
X1127696D03*
X1121397Y659213D03*
X1124547D03*
X1127696D03*
X1121397Y665512D03*
X1124547D03*
X1127696D03*
X1121397Y725355D03*
X1124547D03*
X1127696D03*
X1121397Y722205D03*
X1124547D03*
X1127696D03*
X1121397Y719056D03*
X1124547D03*
X1127696D03*
X1181240Y662363D03*
Y659213D03*
Y665512D03*
Y725355D03*
Y722205D03*
Y719056D03*
X1184389Y662363D03*
X1187539D03*
X1184389Y659213D03*
X1187539D03*
X1184389Y665512D03*
X1187539D03*
X1184389Y725355D03*
X1187539D03*
X1184389Y722205D03*
X1187539D03*
X1184389Y719056D03*
X1187539D03*
G54D74*
X323214Y74290D03*
G54D39*
X146364Y290190D03*
X135364D03*
X305100Y36200D03*
Y27500D03*
Y44800D03*
X316100Y36200D03*
Y27500D03*
Y44800D03*
X829500Y452500D03*
X840500D03*
X869000Y379500D03*
X880000D03*
X1038000Y80500D03*
Y89500D03*
Y98500D03*
X1049000Y80500D03*
Y89500D03*
Y98500D03*
X1054000Y923500D03*
X1043000D03*
X1283500Y371000D03*
Y380000D03*
X1294500Y371000D03*
Y380000D03*
X1313000Y371000D03*
X1302000D03*
X1313000Y380000D03*
X1302000D03*
X1362000Y371500D03*
Y362500D03*
X1373000Y371500D03*
Y362500D03*
G54D93*
X639300Y612460D03*
Y609900D03*
Y607340D03*
X646700D03*
Y609900D03*
Y612460D03*
X866200Y636940D03*
Y639500D03*
Y642060D03*
X858800D03*
Y639500D03*
Y636940D03*
G54D57*
X226921Y848750D03*
X224953D03*
X222984D03*
X221016D03*
X219047D03*
X217079D03*
Y868250D03*
X219047D03*
X221016D03*
X222984D03*
X224953D03*
X226921D03*
G54D75*
X317564Y80195D03*
Y76258D03*
Y78227D03*
X334280Y80195D03*
Y78227D03*
Y76258D03*
Y74290D03*
G54D48*
X171800Y666500D03*
X315700Y56700D03*
Y51700D03*
Y61700D03*
X385800Y943000D03*
X437855Y290600D03*
X688300Y473000D03*
X765548Y123500D03*
X789800Y897000D03*
X793574Y434078D03*
X812074Y465078D03*
X881800Y330000D03*
X1056516Y277968D03*
X1056300Y283000D03*
X1073300Y141000D03*
X1084800Y412000D03*
X1097300Y61000D03*
Y66500D03*
X1116300Y280000D03*
X1145768Y252784D03*
X1150800Y592500D03*
X1152300Y827000D03*
X1186870Y777000D03*
X1227800Y452500D03*
X1254000Y209700D03*
X1254800Y675500D03*
X1281800Y569000D03*
X1291712Y434712D03*
X1309800Y363000D03*
X1350300Y420000D03*
X1353917Y562412D03*
G54D66*
X286359Y430678D03*
X294959Y426938D03*
Y434418D03*
G54D84*
X360433Y140945D03*
X357284D03*
X360433Y144094D03*
X357284D03*
X360433Y147244D03*
X357284D03*
X360433Y150393D03*
X357284D03*
X360433Y153543D03*
X357284D03*
X360433Y156693D03*
X357284D03*
X360433Y159842D03*
X357284D03*
X360433Y162992D03*
X357284D03*
X360433Y166141D03*
X357284D03*
X360433Y169291D03*
X357284D03*
X360433Y172441D03*
X357284D03*
X360433Y175590D03*
X357284D03*
X360433Y178740D03*
X357284D03*
X360433Y181889D03*
X357284D03*
X360433Y185039D03*
X357284D03*
X360433Y188189D03*
X357284D03*
X360433Y191338D03*
X357284D03*
X360433Y194488D03*
X357284D03*
X360433Y197637D03*
X357284D03*
X360433Y200787D03*
X357284D03*
X360433Y203937D03*
X357284D03*
X360433Y207086D03*
X357284D03*
X360433Y210236D03*
X357284D03*
X360433Y213385D03*
X357284D03*
X379331Y131496D03*
X376181D03*
X373032D03*
X369882D03*
X366733D03*
X379331Y134645D03*
X376181D03*
X373032D03*
X369882D03*
X366733D03*
X379331Y137795D03*
X376181D03*
X373032D03*
X369882D03*
X366733D03*
X379331Y140945D03*
X376181D03*
X373032D03*
X369882D03*
X366733D03*
X363583D03*
X379331Y144094D03*
X376181D03*
X373032D03*
X369882D03*
X366733D03*
X363583D03*
X379331Y147244D03*
X376181D03*
X373032D03*
X369882D03*
X366733D03*
X363583D03*
X379331Y150393D03*
X376181D03*
X373032D03*
X369882D03*
X366733D03*
X363583D03*
X379331Y153543D03*
X376181D03*
X373032D03*
X369882D03*
X366733D03*
X363583D03*
X379331Y156693D03*
X376181D03*
X373032D03*
X369882D03*
X366733D03*
X363583D03*
X379331Y159842D03*
X376181D03*
X373032D03*
X369882D03*
X366733D03*
X363583D03*
X379331Y162992D03*
X376181D03*
X373032D03*
X369882D03*
X366733D03*
X363583D03*
X379331Y166141D03*
X376181D03*
X373032D03*
X369882D03*
X366733D03*
X363583D03*
X379331Y169291D03*
X376181D03*
X373032D03*
X369882D03*
X366733D03*
X363583D03*
X379331Y172441D03*
X376181D03*
X373032D03*
X369882D03*
X366733D03*
X363583D03*
X379331Y175590D03*
X376181D03*
X373032D03*
X369882D03*
X366733D03*
X363583D03*
X379331Y178740D03*
X376181D03*
X373032D03*
X369882D03*
X366733D03*
X363583D03*
X379331Y181889D03*
X376181D03*
X373032D03*
X369882D03*
X366733D03*
X363583D03*
X379331Y185039D03*
X376181D03*
X373032D03*
X369882D03*
X366733D03*
X363583D03*
X379331Y188189D03*
X376181D03*
X373032D03*
X369882D03*
X366733D03*
X363583D03*
X379331Y191338D03*
X376181D03*
X373032D03*
X369882D03*
X366733D03*
X363583D03*
X379331Y194488D03*
X376181D03*
X373032D03*
X369882D03*
X366733D03*
X363583D03*
X379331Y197637D03*
X376181D03*
X373032D03*
X369882D03*
X366733D03*
X363583D03*
X379331Y200787D03*
X376181D03*
X373032D03*
X369882D03*
X366733D03*
X363583D03*
X379331Y203937D03*
X376181D03*
X373032D03*
X369882D03*
X366733D03*
X363583D03*
X379331Y207086D03*
X376181D03*
X373032D03*
X369882D03*
X366733D03*
X363583D03*
X379331Y210236D03*
X376181D03*
X373032D03*
X369882D03*
X366733D03*
X363583D03*
X379331Y213385D03*
X376181D03*
X373032D03*
X369882D03*
X366733D03*
X363583D03*
X379331Y216535D03*
X376181D03*
X373032D03*
X369882D03*
X366733D03*
X379331Y219685D03*
X376181D03*
X373032D03*
X369882D03*
X366733D03*
X379331Y222834D03*
X376181D03*
X373032D03*
X369882D03*
X366733D03*
X395079Y131496D03*
X391929D03*
X388780D03*
X385630D03*
X382481D03*
X395079Y134645D03*
X391929D03*
X388780D03*
X385630D03*
X382481D03*
X395079Y137795D03*
X391929D03*
X388780D03*
X385630D03*
X382481D03*
X395079Y140945D03*
X391929D03*
X388780D03*
X385630D03*
X382481D03*
X395079Y144094D03*
X391929D03*
X388780D03*
X385630D03*
X382481D03*
X395079Y147244D03*
X391929D03*
X388780D03*
X385630D03*
X382481D03*
X395079Y150393D03*
X391929D03*
X388780D03*
X385630D03*
X382481D03*
X395079Y153543D03*
X391929D03*
X388780D03*
X385630D03*
X382481D03*
X395079Y156693D03*
X391929D03*
X388780D03*
X385630D03*
X382481D03*
X395079Y159842D03*
X391929D03*
X388780D03*
X385630D03*
X382481D03*
X395079Y162992D03*
X391929D03*
X388780D03*
X385630D03*
X382481D03*
X395079Y166141D03*
X391929D03*
X388780D03*
X385630D03*
X382481D03*
X395079Y169291D03*
X391929D03*
X388780D03*
X385630D03*
X382481D03*
X395079Y172441D03*
X391929D03*
X388780D03*
X385630D03*
X382481D03*
X395079Y175590D03*
X391929D03*
X388780D03*
X385630D03*
X382481D03*
X395079Y178740D03*
X391929D03*
X388780D03*
X385630D03*
X382481D03*
X395079Y181889D03*
X391929D03*
X388780D03*
X385630D03*
X382481D03*
X395079Y185039D03*
X391929D03*
X388780D03*
X385630D03*
X382481D03*
X395079Y188189D03*
X391929D03*
X388780D03*
X385630D03*
X382481D03*
X395079Y191338D03*
X391929D03*
X388780D03*
X385630D03*
X382481D03*
X395079Y194488D03*
X391929D03*
X388780D03*
X385630D03*
X382481D03*
X395079Y197637D03*
X391929D03*
X388780D03*
X385630D03*
X382481D03*
X395079Y200787D03*
X391929D03*
X388780D03*
X385630D03*
X382481D03*
X395079Y203937D03*
X391929D03*
X388780D03*
X385630D03*
X382481D03*
X395079Y207086D03*
X391929D03*
X388780D03*
X385630D03*
X382481D03*
X395079Y210236D03*
X391929D03*
X388780D03*
X385630D03*
X382481D03*
X395079Y213385D03*
X391929D03*
X388780D03*
X385630D03*
X382481D03*
X395079Y216535D03*
X391929D03*
X388780D03*
X385630D03*
X382481D03*
X395079Y219685D03*
X391929D03*
X388780D03*
X385630D03*
X382481D03*
X395079Y222834D03*
X391929D03*
X388780D03*
X385630D03*
X382481D03*
X410827Y131496D03*
X407677D03*
X404528D03*
X401378D03*
X398229D03*
X410827Y134645D03*
X407677D03*
X404528D03*
X401378D03*
X398229D03*
X410827Y137795D03*
X407677D03*
X404528D03*
X401378D03*
X398229D03*
X410827Y140945D03*
X407677D03*
X404528D03*
X401378D03*
X398229D03*
X410827Y144094D03*
X407677D03*
X404528D03*
X401378D03*
X398229D03*
X410827Y147244D03*
X407677D03*
X404528D03*
X401378D03*
X398229D03*
X410827Y150393D03*
X407677D03*
X404528D03*
X401378D03*
X398229D03*
X410827Y153543D03*
X407677D03*
X404528D03*
X401378D03*
X398229D03*
X410827Y156693D03*
X407677D03*
X404528D03*
X401378D03*
X398229D03*
X410827Y159842D03*
X407677D03*
X404528D03*
X401378D03*
X398229D03*
X410827Y162992D03*
X407677D03*
X404528D03*
X401378D03*
X398229D03*
X410827Y166141D03*
X407677D03*
X404528D03*
X401378D03*
X398229D03*
X410827Y169291D03*
X407677D03*
X404528D03*
X401378D03*
X398229D03*
X410827Y172441D03*
X407677D03*
X404528D03*
X401378D03*
X398229D03*
X410827Y175590D03*
X407677D03*
X404528D03*
X401378D03*
X398229D03*
X410827Y178740D03*
X407677D03*
X404528D03*
X401378D03*
X398229D03*
X410827Y181889D03*
X407677D03*
X404528D03*
X401378D03*
X398229D03*
X410827Y185039D03*
X407677D03*
X404528D03*
X401378D03*
X398229D03*
X410827Y188189D03*
X407677D03*
X404528D03*
X401378D03*
X398229D03*
X410827Y191338D03*
X407677D03*
X404528D03*
X401378D03*
X398229D03*
X410827Y194488D03*
X407677D03*
X404528D03*
X401378D03*
X398229D03*
X410827Y197637D03*
X407677D03*
X404528D03*
X401378D03*
X398229D03*
X410827Y200787D03*
X407677D03*
X404528D03*
X401378D03*
X398229D03*
X410827Y203937D03*
X407677D03*
X404528D03*
X401378D03*
X398229D03*
X410827Y207086D03*
X407677D03*
X404528D03*
X401378D03*
X398229D03*
X410827Y210236D03*
X407677D03*
X404528D03*
X401378D03*
X398229D03*
X410827Y213385D03*
X407677D03*
X404528D03*
X401378D03*
X398229D03*
X410827Y216535D03*
X407677D03*
X404528D03*
X401378D03*
X398229D03*
X410827Y219685D03*
X407677D03*
X404528D03*
X401378D03*
X398229D03*
X410827Y222834D03*
X407677D03*
X404528D03*
X401378D03*
X398229D03*
X426575Y131496D03*
X423425D03*
X420276D03*
X417126D03*
X413977D03*
X426575Y134645D03*
X423425D03*
X420276D03*
X417126D03*
X413977D03*
X426575Y137795D03*
X423425D03*
X420276D03*
X417126D03*
X413977D03*
X426575Y140945D03*
X423425D03*
X420276D03*
X417126D03*
X413977D03*
X426575Y144094D03*
X423425D03*
X420276D03*
X417126D03*
X413977D03*
X426575Y147244D03*
X423425D03*
X420276D03*
X417126D03*
X413977D03*
X426575Y150393D03*
X423425D03*
X420276D03*
X417126D03*
X413977D03*
X426575Y153543D03*
X423425D03*
X420276D03*
X417126D03*
X413977D03*
X426575Y156693D03*
X423425D03*
X420276D03*
X417126D03*
X413977D03*
X426575Y159842D03*
X423425D03*
X420276D03*
X417126D03*
X413977D03*
X426575Y162992D03*
X423425D03*
X420276D03*
X417126D03*
X413977D03*
X426575Y166141D03*
X423425D03*
X420276D03*
X417126D03*
X413977D03*
X426575Y169291D03*
X423425D03*
X420276D03*
X417126D03*
X413977D03*
X426575Y172441D03*
X423425D03*
X420276D03*
X417126D03*
X413977D03*
X426575Y175590D03*
X423425D03*
X420276D03*
X417126D03*
X413977D03*
X426575Y178740D03*
X423425D03*
X420276D03*
X417126D03*
X413977D03*
X426575Y181889D03*
X423425D03*
X420276D03*
X417126D03*
X413977D03*
X426575Y185039D03*
X423425D03*
X420276D03*
X417126D03*
X413977D03*
X426575Y188189D03*
X423425D03*
X420276D03*
X417126D03*
X413977D03*
X426575Y191338D03*
X423425D03*
X420276D03*
X417126D03*
X413977D03*
X426575Y194488D03*
X423425D03*
X420276D03*
X417126D03*
X413977D03*
X426575Y197637D03*
X423425D03*
X420276D03*
X417126D03*
X413977D03*
X426575Y200787D03*
X423425D03*
X420276D03*
X417126D03*
X413977D03*
X426575Y203937D03*
X423425D03*
X420276D03*
X417126D03*
X413977D03*
X426575Y207086D03*
X423425D03*
X420276D03*
X417126D03*
X413977D03*
X426575Y210236D03*
X423425D03*
X420276D03*
X417126D03*
X413977D03*
X426575Y213385D03*
X423425D03*
X420276D03*
X417126D03*
X413977D03*
X426575Y216535D03*
X423425D03*
X420276D03*
X417126D03*
X413977D03*
X426575Y219685D03*
X423425D03*
X420276D03*
X417126D03*
X413977D03*
X426575Y222834D03*
X423425D03*
X420276D03*
X417126D03*
X413977D03*
X439173Y131496D03*
X436024D03*
X432874D03*
X429725D03*
X439173Y134645D03*
X436024D03*
X432874D03*
X429725D03*
X439173Y137795D03*
X436024D03*
X432874D03*
X429725D03*
X442323Y140945D03*
X439173D03*
X436024D03*
X432874D03*
X429725D03*
X442323Y144094D03*
X439173D03*
X436024D03*
X432874D03*
X429725D03*
X442323Y147244D03*
X439173D03*
X436024D03*
X432874D03*
X429725D03*
X442323Y150393D03*
X439173D03*
X436024D03*
X432874D03*
X429725D03*
X442323Y153543D03*
X439173D03*
X436024D03*
X432874D03*
X429725D03*
X442323Y156693D03*
X439173D03*
X436024D03*
X432874D03*
X429725D03*
X442323Y159842D03*
X439173D03*
X436024D03*
X432874D03*
X429725D03*
X442323Y162992D03*
X439173D03*
X436024D03*
X432874D03*
X429725D03*
X442323Y166141D03*
X439173D03*
X436024D03*
X432874D03*
X429725D03*
X442323Y169291D03*
X439173D03*
X436024D03*
X432874D03*
X429725D03*
X442323Y172441D03*
X439173D03*
X436024D03*
X432874D03*
X429725D03*
X442323Y175590D03*
X439173D03*
X436024D03*
X432874D03*
X429725D03*
X442323Y178740D03*
X439173D03*
X436024D03*
X432874D03*
X429725D03*
X442323Y181889D03*
X439173D03*
X436024D03*
X432874D03*
X429725D03*
X442323Y185039D03*
X439173D03*
X436024D03*
X432874D03*
X429725D03*
X442323Y188189D03*
X439173D03*
X436024D03*
X432874D03*
X429725D03*
X442323Y191338D03*
X439173D03*
X436024D03*
X432874D03*
X429725D03*
X442323Y194488D03*
X439173D03*
X436024D03*
X432874D03*
X429725D03*
X442323Y197637D03*
X439173D03*
X436024D03*
X432874D03*
X429725D03*
X442323Y200787D03*
X439173D03*
X436024D03*
X432874D03*
X429725D03*
X442323Y203937D03*
X439173D03*
X436024D03*
X432874D03*
X429725D03*
X442323Y207086D03*
X439173D03*
X436024D03*
X432874D03*
X429725D03*
X442323Y210236D03*
X439173D03*
X436024D03*
X432874D03*
X429725D03*
X442323Y213385D03*
X439173D03*
X436024D03*
X432874D03*
X429725D03*
X439173Y216535D03*
X436024D03*
X432874D03*
X429725D03*
X439173Y219685D03*
X436024D03*
X432874D03*
X429725D03*
X439173Y222834D03*
X436024D03*
X432874D03*
X429725D03*
X448622Y140945D03*
X445473D03*
X448622Y144094D03*
X445473D03*
X448622Y147244D03*
X445473D03*
X448622Y150393D03*
X445473D03*
X448622Y153543D03*
X445473D03*
X448622Y156693D03*
X445473D03*
X448622Y159842D03*
X445473D03*
X448622Y162992D03*
X445473D03*
X448622Y166141D03*
X445473D03*
X448622Y169291D03*
X445473D03*
X448622Y172441D03*
X445473D03*
X448622Y175590D03*
X445473D03*
X448622Y178740D03*
X445473D03*
X448622Y181889D03*
X445473D03*
X448622Y185039D03*
X445473D03*
X448622Y188189D03*
X445473D03*
X448622Y191338D03*
X445473D03*
X448622Y194488D03*
X445473D03*
X448622Y197637D03*
X445473D03*
X448622Y200787D03*
X445473D03*
X448622Y203937D03*
X445473D03*
X448622Y207086D03*
X445473D03*
X448622Y210236D03*
X445473D03*
X448622Y213385D03*
X445473D03*
X1130846Y662363D03*
X1133996D03*
X1130846Y659213D03*
X1133996D03*
X1121397Y678111D03*
X1124547D03*
X1127696D03*
X1130846D03*
X1133996D03*
X1121397Y674961D03*
X1124547D03*
X1127696D03*
X1130846D03*
X1133996D03*
X1121397Y671812D03*
X1124547D03*
X1127696D03*
X1130846D03*
X1133996D03*
X1121397Y668662D03*
X1124547D03*
X1127696D03*
X1130846D03*
X1133996D03*
X1130846Y665512D03*
X1133996D03*
X1121397Y697008D03*
X1124547D03*
X1127696D03*
X1130846D03*
X1133996D03*
X1121397Y693859D03*
X1124547D03*
X1127696D03*
X1130846D03*
X1133996D03*
X1121397Y690709D03*
X1124547D03*
X1127696D03*
X1130846D03*
X1133996D03*
X1121397Y687560D03*
X1124547D03*
X1127696D03*
X1130846D03*
X1133996D03*
X1121397Y684410D03*
X1124547D03*
X1127696D03*
X1130846D03*
X1133996D03*
X1121397Y681260D03*
X1124547D03*
X1127696D03*
X1130846D03*
X1133996D03*
X1121397Y712756D03*
X1124547D03*
X1127696D03*
X1130846D03*
X1133996D03*
X1121397Y709607D03*
X1124547D03*
X1127696D03*
X1130846D03*
X1133996D03*
X1121397Y706457D03*
X1124547D03*
X1127696D03*
X1130846D03*
X1133996D03*
X1121397Y703308D03*
X1124547D03*
X1127696D03*
X1130846D03*
X1133996D03*
X1121397Y700158D03*
X1124547D03*
X1127696D03*
X1130846D03*
X1133996D03*
X1130846Y725355D03*
X1133996D03*
X1130846Y722205D03*
X1133996D03*
X1130846Y719056D03*
X1133996D03*
X1121397Y715906D03*
X1124547D03*
X1127696D03*
X1130846D03*
X1133996D03*
X1121646Y772186D03*
Y775335D03*
Y778485D03*
X1124796Y772186D03*
Y775335D03*
Y778485D03*
X1127945Y772186D03*
Y775335D03*
Y778485D03*
X1131095Y772186D03*
Y775335D03*
Y778485D03*
X1134244Y772186D03*
Y775335D03*
Y778485D03*
X1121646Y791083D03*
Y794233D03*
X1124796Y791083D03*
Y794233D03*
X1127945Y791083D03*
Y794233D03*
X1131095Y791083D03*
Y794233D03*
X1134244Y791083D03*
Y794233D03*
X1121646Y797382D03*
X1124796D03*
X1127945D03*
X1131095D03*
X1134244D03*
X1137145Y662363D03*
X1140295D03*
X1143444D03*
X1146594D03*
X1149744D03*
X1137145Y659213D03*
X1140295D03*
X1143444D03*
X1146594D03*
X1149744D03*
X1143444Y674961D03*
X1146594D03*
X1149744D03*
X1137145Y671812D03*
X1140295D03*
X1143444D03*
X1146594D03*
X1149744D03*
X1137145Y668662D03*
X1140295D03*
X1143444D03*
X1146594D03*
X1149744D03*
X1137145Y665512D03*
X1140295D03*
X1143444D03*
X1146594D03*
X1149744D03*
X1137145Y697008D03*
X1146594D03*
X1149744D03*
X1137145Y693859D03*
X1146594D03*
X1149744D03*
X1137145Y690709D03*
X1146594D03*
X1149744D03*
X1137145Y687560D03*
X1146594D03*
X1149744D03*
X1137145Y684410D03*
X1146594D03*
X1149744D03*
X1137145Y681260D03*
Y712756D03*
X1140295D03*
X1143444D03*
X1146594D03*
X1149744D03*
X1143444Y709607D03*
X1146594D03*
X1149744D03*
X1137145Y703308D03*
Y700158D03*
X1146594D03*
X1149744D03*
X1137145Y725355D03*
X1140295D03*
X1143444D03*
X1146594D03*
X1149744D03*
X1137145Y722205D03*
X1140295D03*
X1143444D03*
X1146594D03*
X1149744D03*
X1137145Y719056D03*
X1140295D03*
X1143444D03*
X1146594D03*
X1149744D03*
X1137145Y715906D03*
X1140295D03*
X1143444D03*
X1146594D03*
X1149744D03*
X1137394Y772186D03*
Y775335D03*
Y778485D03*
X1140544Y772186D03*
Y775335D03*
Y778485D03*
X1143693Y772186D03*
Y775335D03*
Y778485D03*
X1146843Y772186D03*
Y775335D03*
Y778485D03*
X1149992Y772186D03*
Y775335D03*
Y778485D03*
X1137394Y791083D03*
Y794233D03*
X1140544Y791083D03*
Y794233D03*
X1143693Y791083D03*
Y794233D03*
X1146843Y791083D03*
Y794233D03*
X1149992Y791083D03*
Y794233D03*
X1137394Y797382D03*
X1140544D03*
X1143693D03*
X1146843D03*
X1149992D03*
X1152893Y662363D03*
X1156043D03*
X1159192D03*
X1162342D03*
X1165492D03*
X1152893Y659213D03*
X1156043D03*
X1159192D03*
X1162342D03*
X1165492D03*
X1152893Y674961D03*
X1156043D03*
X1159192D03*
X1162342D03*
X1165492D03*
X1152893Y671812D03*
X1156043D03*
X1159192D03*
X1162342D03*
X1165492D03*
X1152893Y668662D03*
X1156043D03*
X1159192D03*
X1162342D03*
X1165492D03*
X1152893Y665512D03*
X1156043D03*
X1159192D03*
X1162342D03*
X1165492D03*
X1152893Y697008D03*
X1156043D03*
X1159192D03*
X1162342D03*
X1152893Y693859D03*
X1156043D03*
X1159192D03*
X1162342D03*
X1152893Y690709D03*
X1156043D03*
X1159192D03*
X1162342D03*
X1152893Y687560D03*
X1156043D03*
X1159192D03*
X1162342D03*
X1152893Y684410D03*
X1156043D03*
X1159192D03*
X1162342D03*
X1152893Y712756D03*
X1156043D03*
X1159192D03*
X1162342D03*
X1165492D03*
X1152893Y709607D03*
X1156043D03*
X1159192D03*
X1162342D03*
X1165492D03*
X1152893Y700158D03*
X1156043D03*
X1159192D03*
X1162342D03*
X1152893Y725355D03*
X1156043D03*
X1159192D03*
X1162342D03*
X1165492D03*
X1152893Y722205D03*
X1156043D03*
X1159192D03*
X1162342D03*
X1165492D03*
X1152893Y719056D03*
X1156043D03*
X1159192D03*
X1162342D03*
X1165492D03*
X1152893Y715906D03*
X1156043D03*
X1159192D03*
X1162342D03*
X1165492D03*
X1153142Y772186D03*
Y775335D03*
Y778485D03*
X1156292Y772186D03*
Y775335D03*
Y778485D03*
X1159441Y772186D03*
Y775335D03*
Y778485D03*
X1162591Y772186D03*
Y775335D03*
Y778485D03*
X1165740Y772186D03*
Y775335D03*
Y778485D03*
X1153142Y791083D03*
Y794233D03*
X1156292Y791083D03*
Y794233D03*
X1159441Y791083D03*
Y794233D03*
X1162591Y791083D03*
Y794233D03*
X1165740Y791083D03*
Y794233D03*
X1153142Y797382D03*
X1156292D03*
X1159441D03*
X1162591D03*
X1165740D03*
X1168641Y662363D03*
X1171791D03*
X1174940D03*
X1178090D03*
X1168641Y659213D03*
X1171791D03*
X1174940D03*
X1178090D03*
X1174940Y678111D03*
X1178090D03*
X1181240D03*
X1174940Y674961D03*
X1178090D03*
X1181240D03*
X1168641Y671812D03*
X1171791D03*
X1174940D03*
X1178090D03*
X1181240D03*
X1168641Y668662D03*
X1171791D03*
X1174940D03*
X1178090D03*
X1181240D03*
X1168641Y665512D03*
X1171791D03*
X1174940D03*
X1178090D03*
X1171791Y697008D03*
X1174940D03*
X1178090D03*
X1181240D03*
X1171791Y693859D03*
X1174940D03*
X1178090D03*
X1181240D03*
X1171791Y690709D03*
X1174940D03*
X1178090D03*
X1181240D03*
X1171791Y687560D03*
X1174940D03*
X1178090D03*
X1181240D03*
X1171791Y684410D03*
X1174940D03*
X1178090D03*
X1181240D03*
X1171791Y681260D03*
X1174940D03*
X1178090D03*
X1181240D03*
X1168641Y712756D03*
X1171791D03*
X1174940D03*
X1178090D03*
X1181240D03*
X1174940Y709607D03*
X1178090D03*
X1181240D03*
X1174940Y706457D03*
X1178090D03*
X1181240D03*
X1171791Y703308D03*
X1174940D03*
X1178090D03*
X1181240D03*
X1171791Y700158D03*
X1174940D03*
X1178090D03*
X1181240D03*
X1168641Y725355D03*
X1171791D03*
X1174940D03*
X1178090D03*
X1168641Y722205D03*
X1171791D03*
X1174940D03*
X1178090D03*
X1168641Y719056D03*
X1171791D03*
X1174940D03*
X1178090D03*
X1168641Y715906D03*
X1171791D03*
X1174940D03*
X1178090D03*
X1181240D03*
X1168890Y772186D03*
Y775335D03*
Y778485D03*
Y791083D03*
Y794233D03*
Y797382D03*
X1184389Y678111D03*
X1187539D03*
X1184389Y674961D03*
X1187539D03*
X1184389Y671812D03*
X1187539D03*
X1184389Y668662D03*
X1187539D03*
X1184389Y697008D03*
X1187539D03*
X1184389Y693859D03*
X1187539D03*
X1184389Y690709D03*
X1187539D03*
X1184389Y687560D03*
X1187539D03*
X1184389Y684410D03*
X1187539D03*
X1184389Y681260D03*
X1187539D03*
X1184389Y712756D03*
X1187539D03*
X1184389Y709607D03*
X1187539D03*
X1184389Y706457D03*
X1187539D03*
X1184389Y703308D03*
X1187539D03*
X1184389Y700158D03*
X1187539D03*
X1184389Y715906D03*
X1187539D03*
G54D49*
X184200Y861000D03*
X187700Y852000D03*
X188200Y874000D03*
X209700Y816500D03*
X452629Y101500D03*
X596598Y426116D03*
Y431116D03*
Y441116D03*
Y436116D03*
Y451116D03*
Y446116D03*
X670948Y56500D03*
Y63500D03*
X719400Y202000D03*
X763974Y441078D03*
X846700Y720000D03*
X870168Y709784D03*
X1038700Y105500D03*
Y111000D03*
X1100700Y780500D03*
X1147100Y604700D03*
X1249200Y716000D03*
X1287700Y363000D03*
X1302700Y564500D03*
X1311817Y577412D03*
X1325200Y420000D03*
X1336817Y562412D03*
G54D67*
X302750Y18000D03*
X318250D03*
G54D58*
X222000Y858500D03*
G54D94*
X655850Y462500D03*
G54D76*
X321001Y83632D03*
X319032D03*
X322969D03*
X324938D03*
X326906D03*
X328875D03*
X332812D03*
X330843D03*
G54D85*
X357429Y237500D03*
X352929Y242000D03*
X361929D03*
X375429Y237500D03*
X366429Y238000D03*
X370929Y242000D03*
X378429D03*
X374000Y392500D03*
X369500Y401000D03*
X370155Y463000D03*
X381429Y237500D03*
X386500D03*
X388055Y307500D03*
X384055Y311500D03*
Y317000D03*
X392555Y309500D03*
X386555Y333000D03*
X384055Y339500D03*
Y371000D03*
X380500Y393000D03*
X385023Y387783D03*
X388023Y412283D03*
X387555Y459700D03*
X394155Y460000D03*
X390555Y455500D03*
X406055Y307500D03*
X401555Y309500D03*
X411555D03*
X397055Y307500D03*
X427000Y111000D03*
X416200Y245300D03*
X429429Y252900D03*
X416555Y307500D03*
X425755Y309800D03*
X429355Y306100D03*
X440000Y115000D03*
X434000Y244500D03*
X438000Y300500D03*
X439055Y309900D03*
X445855Y309200D03*
X437155Y305300D03*
X442155Y306000D03*
X432955Y309700D03*
X459000Y302000D03*
X448000Y304500D03*
X452055Y308500D03*
X457055Y308000D03*
X460055Y312000D03*
X463000Y117500D03*
X465500Y122500D03*
X466000Y137000D03*
X462429Y133500D03*
X466000Y130000D03*
X462500Y126500D03*
X463500Y141500D03*
X465055Y313500D03*
X524635Y212188D03*
X538500Y160000D03*
X567429Y159500D03*
X704933Y98147D03*
X699716Y137284D03*
X693055Y261500D03*
X692555Y267500D03*
X724716Y94784D03*
X710748Y100000D03*
X737000Y90000D03*
X746500Y105000D03*
X748248Y118500D03*
X982500Y397500D03*
X1050000Y669500D03*
X1056000Y673500D03*
X1087200Y664900D03*
X1096500Y717000D03*
X1101500Y718000D03*
X1095900Y722000D03*
X1101100Y723000D03*
X1099550Y838740D03*
X1106500Y718100D03*
X1106200Y723100D03*
X1120000Y629500D03*
X1124000Y644500D03*
X1120000Y634500D03*
X1120500Y639500D03*
X1139500Y644500D03*
Y639500D03*
X1182000Y643000D03*
X1191500Y631000D03*
X1193500Y626500D03*
X1188000Y634500D03*
X1185500Y639500D03*
X1203000Y645500D03*
X1212000Y685000D03*
X1213000Y712500D03*
X1208500Y710500D03*
X1202000Y709000D03*
X1206500Y706000D03*
X1207000Y715500D03*
X1202500Y727500D03*
X1202000Y720000D03*
X1207000Y720500D03*
X1202000Y715000D03*
X1226500Y767500D03*
X1242500Y588000D03*
X1243500Y679000D03*
X1236500Y757500D03*
X1241500Y757000D03*
X1237000Y750000D03*
X1354117Y574912D03*
X1350017Y615812D03*
G54D59*
X224297Y905248D03*
X230703D03*
G54D86*
X373894Y7992D03*
X386264D03*
X421138D03*
X433508D03*
G54D77*
X326385Y218372D03*
X328585D03*
X326385Y221872D03*
X328585D03*
X404829Y241900D03*
X407029D03*
X404829Y245400D03*
X407029D03*
X519423Y324783D03*
X521623D03*
X519423Y327283D03*
X521623D03*
X525423Y330283D03*
Y332783D03*
X514923Y332283D03*
X517123D03*
X514923Y334783D03*
X517123D03*
X515900Y343500D03*
X518100D03*
X515900Y346000D03*
X518100D03*
X515900Y348500D03*
X518100D03*
X515900Y351000D03*
X518100D03*
X515900Y353500D03*
X518100D03*
X515900Y356000D03*
X518100D03*
X515900Y359500D03*
X518100D03*
X515900Y362000D03*
X518100D03*
X527623Y330283D03*
Y332783D03*
G54D68*
X303150Y81500D03*
X817924Y465078D03*
X1027650Y155000D03*
X1249650Y445000D03*
G54D95*
X653150Y462500D03*
G54D96*
X672600Y348500D03*
Y369000D03*
X697400Y348500D03*
Y369000D03*
G54D78*
X339500Y35400D03*
Y57600D03*
G54D69*
X305850Y81500D03*
X820624Y465078D03*
X1030350Y155000D03*
X1252350Y445000D03*
G54D87*
G01X-245081Y-422119D02*
G02I-12000J0D01*
G01X-250231D02*
G02I-6850J0D01*
G01X-241081D02*
X-273081D01*
G01X-257081Y-438119D02*
Y-406119D01*
G01X-241081Y-438119D02*
Y-518119D01*
G01D02*
X1034819D01*
G01X-241081Y-473619D02*
X1034819D01*
G01X-241081Y-438119D02*
X1034819D01*
G01X247319D02*
Y-518119D01*
G01X384819Y-438119D02*
Y-518119D01*
G01X499819Y-438119D02*
Y-518119D01*
G01X667319Y-438119D02*
Y-518119D01*
G01X837319Y-438119D02*
Y-518119D01*
G01X1034819Y-438119D02*
Y-518119D01*
G01X1066819Y-422119D02*
X1034819D01*
G01X1050819Y-438119D02*
Y-406119D01*
G01X1062819Y-422119D02*
G02I-12000J0D01*
G01X1057669D02*
G02I-6850J0D01*
X410826Y332086D03*
Y328149D03*
Y324212D03*
X406889Y332086D03*
Y328149D03*
Y324212D03*
X402952Y332086D03*
Y328149D03*
X410826Y414764D03*
X406889D03*
X402952D03*
X410826Y422638D03*
Y418701D03*
X406889Y422638D03*
Y418701D03*
X402952D03*
X493504Y332086D03*
Y328149D03*
Y324212D03*
Y414764D03*
Y422638D03*
Y418701D03*
X501378Y332086D03*
Y328149D03*
X497441Y332086D03*
Y328149D03*
Y324212D03*
X501378Y414764D03*
X497441D03*
X501378Y418701D03*
X497441Y422638D03*
Y418701D03*
G54D79*
X332000Y123900D03*
Y126100D03*
X334500Y123900D03*
Y126100D03*
X342429Y330900D03*
Y333100D03*
X346429Y330900D03*
Y333100D03*
X342429Y345400D03*
Y347600D03*
X345929Y345400D03*
Y347600D03*
Y358900D03*
Y361100D03*
X342429Y358900D03*
Y361100D03*
X343555Y439900D03*
Y442100D03*
X339555Y439900D03*
Y442100D03*
X335555Y439900D03*
Y442100D03*
X331555Y439900D03*
Y442100D03*
X359555Y439900D03*
Y442100D03*
X355555Y439900D03*
Y442100D03*
X351555Y439900D03*
Y442100D03*
X347555Y439900D03*
Y442100D03*
X367000Y439900D03*
Y442100D03*
X363555Y439900D03*
Y442100D03*
X407555Y448900D03*
Y451100D03*
X410055Y448900D03*
Y451100D03*
X400555Y448900D03*
Y451100D03*
X403055Y448900D03*
Y451100D03*
X428555Y448900D03*
Y451100D03*
X424055Y448900D03*
Y451100D03*
X421555Y448900D03*
Y451100D03*
X417055Y448900D03*
Y451100D03*
X414555Y448900D03*
Y451100D03*
X445055Y448900D03*
Y451100D03*
X442555Y448900D03*
Y451100D03*
X438055Y448900D03*
Y451100D03*
X435555Y448900D03*
Y451100D03*
X431055Y448900D03*
Y451100D03*
X459055Y448900D03*
Y451100D03*
X456555Y448900D03*
Y451100D03*
X452055Y448900D03*
Y451100D03*
X449555Y448900D03*
Y451100D03*
X477555Y448900D03*
Y451100D03*
X473055Y448900D03*
Y451100D03*
X470555Y448900D03*
Y451100D03*
X466055Y448900D03*
Y451100D03*
X463555Y448900D03*
Y451100D03*
X480055Y448900D03*
Y451100D03*
X518365Y388360D03*
Y390560D03*
X525055Y387900D03*
Y390100D03*
X522555Y387900D03*
Y390100D03*
X515865Y388360D03*
Y390560D03*
X539000Y387900D03*
Y390100D03*
X536500Y387900D03*
Y390100D03*
X532055Y387900D03*
Y390100D03*
X529555Y387900D03*
Y390100D03*
G54D97*
X678500Y388671D03*
Y420329D03*
G54D88*
X410826Y336023D03*
X406889D03*
X402952D03*
X410826Y351771D03*
Y347834D03*
Y343897D03*
Y339960D03*
X406889Y351771D03*
Y347834D03*
Y343897D03*
Y339960D03*
X402952Y351771D03*
Y347834D03*
Y343897D03*
Y339960D03*
X410826Y367519D03*
Y363582D03*
Y359645D03*
Y355708D03*
X406889Y367519D03*
Y363582D03*
Y359645D03*
Y355708D03*
X402952Y367519D03*
Y363582D03*
Y359645D03*
Y355708D03*
X410826Y383268D03*
Y379331D03*
Y375394D03*
Y371456D03*
X406889Y383268D03*
Y379331D03*
Y375394D03*
Y371456D03*
X402952Y383268D03*
Y379331D03*
Y375394D03*
Y371456D03*
X410826Y399016D03*
Y395079D03*
Y391142D03*
Y387205D03*
X406889Y399016D03*
Y395079D03*
Y391142D03*
Y387205D03*
X402952Y399016D03*
Y395079D03*
Y391142D03*
Y387205D03*
X410826Y410827D03*
Y406890D03*
Y402953D03*
X406889Y410827D03*
Y406890D03*
Y402953D03*
X402952Y410827D03*
Y406890D03*
Y402953D03*
X426574Y336023D03*
Y332086D03*
Y328149D03*
Y324212D03*
X422637Y336023D03*
Y332086D03*
Y328149D03*
Y324212D03*
X418700Y336023D03*
Y332086D03*
Y328149D03*
Y324212D03*
X414763Y336023D03*
Y332086D03*
Y328149D03*
Y324212D03*
X426574Y351771D03*
Y347834D03*
Y343897D03*
Y339960D03*
X422637Y351771D03*
Y347834D03*
Y343897D03*
Y339960D03*
X418700Y351771D03*
Y347834D03*
Y343897D03*
Y339960D03*
X414763Y351771D03*
Y347834D03*
Y343897D03*
Y339960D03*
X426574Y367519D03*
Y363582D03*
Y359645D03*
Y355708D03*
X422637Y367519D03*
Y363582D03*
Y359645D03*
Y355708D03*
X418700Y367519D03*
Y363582D03*
Y359645D03*
Y355708D03*
X414763Y367519D03*
Y363582D03*
Y359645D03*
Y355708D03*
X426574Y383268D03*
Y379331D03*
Y375394D03*
Y371456D03*
X422637Y383268D03*
Y379331D03*
Y375394D03*
Y371456D03*
X418700Y383268D03*
Y379331D03*
Y375394D03*
Y371456D03*
X414763Y383268D03*
Y379331D03*
Y375394D03*
Y371456D03*
X426574Y399016D03*
Y395079D03*
Y391142D03*
Y387205D03*
X422637Y399016D03*
Y395079D03*
Y391142D03*
Y387205D03*
X418700Y399016D03*
Y395079D03*
Y391142D03*
Y387205D03*
X414763Y399016D03*
Y395079D03*
Y391142D03*
Y387205D03*
X426574Y414764D03*
Y410827D03*
Y406890D03*
Y402953D03*
X422637Y414764D03*
Y410827D03*
Y406890D03*
Y402953D03*
X418700Y414764D03*
Y410827D03*
Y406890D03*
Y402953D03*
X414763Y414764D03*
Y410827D03*
Y406890D03*
Y402953D03*
X426574Y422638D03*
Y418701D03*
X422637Y422638D03*
Y418701D03*
X418700Y422638D03*
Y418701D03*
X414763Y422638D03*
Y418701D03*
X442322Y336023D03*
Y332086D03*
Y328149D03*
Y324212D03*
X438385Y336023D03*
Y332086D03*
Y328149D03*
Y324212D03*
X434448Y336023D03*
Y332086D03*
Y328149D03*
Y324212D03*
X430511Y336023D03*
Y332086D03*
Y328149D03*
Y324212D03*
X442322Y351771D03*
Y347834D03*
Y343897D03*
Y339960D03*
X438385Y351771D03*
Y347834D03*
Y343897D03*
Y339960D03*
X434448Y351771D03*
Y347834D03*
Y343897D03*
Y339960D03*
X430511Y351771D03*
Y347834D03*
Y343897D03*
Y339960D03*
X442322Y367519D03*
Y363582D03*
Y359645D03*
Y355708D03*
X438385Y367519D03*
Y363582D03*
Y359645D03*
Y355708D03*
X434448Y367519D03*
Y363582D03*
Y359645D03*
Y355708D03*
X430511Y367519D03*
Y363582D03*
Y359645D03*
Y355708D03*
X442322Y383268D03*
Y379331D03*
Y375394D03*
Y371456D03*
X438385Y383268D03*
Y379331D03*
Y375394D03*
Y371456D03*
X434448Y383268D03*
Y379331D03*
Y375394D03*
Y371456D03*
X430511Y383268D03*
Y379331D03*
Y375394D03*
Y371456D03*
X442322Y399016D03*
Y395079D03*
Y391142D03*
Y387205D03*
X438385Y399016D03*
Y395079D03*
Y391142D03*
Y387205D03*
X434448Y399016D03*
Y395079D03*
Y391142D03*
Y387205D03*
X430511Y399016D03*
Y395079D03*
Y391142D03*
Y387205D03*
X442322Y414764D03*
Y410827D03*
Y406890D03*
Y402953D03*
X438385Y414764D03*
Y410827D03*
Y406890D03*
Y402953D03*
X434448Y414764D03*
Y410827D03*
Y406890D03*
Y402953D03*
X430511Y414764D03*
Y410827D03*
Y406890D03*
Y402953D03*
X442322Y422638D03*
Y418701D03*
X438385Y422638D03*
Y418701D03*
X434448Y422638D03*
Y418701D03*
X430511Y422638D03*
Y418701D03*
X458071Y336023D03*
Y332086D03*
Y328149D03*
Y324212D03*
X454134Y336023D03*
Y332086D03*
Y328149D03*
Y324212D03*
X450196Y336023D03*
Y332086D03*
Y328149D03*
Y324212D03*
X446259Y336023D03*
Y332086D03*
Y328149D03*
Y324212D03*
X458071Y351771D03*
Y347834D03*
Y343897D03*
Y339960D03*
X454134Y351771D03*
Y347834D03*
Y343897D03*
Y339960D03*
X450196Y351771D03*
Y347834D03*
Y343897D03*
Y339960D03*
X446259Y351771D03*
Y347834D03*
Y343897D03*
Y339960D03*
X458071Y367519D03*
Y363582D03*
Y359645D03*
Y355708D03*
X454134Y367519D03*
Y363582D03*
Y359645D03*
Y355708D03*
X450196Y367519D03*
Y363582D03*
Y359645D03*
Y355708D03*
X446259Y367519D03*
Y363582D03*
Y359645D03*
Y355708D03*
X458071Y383268D03*
Y379331D03*
Y375394D03*
Y371456D03*
X454134Y383268D03*
Y379331D03*
Y375394D03*
Y371456D03*
X450196Y383268D03*
Y379331D03*
Y375394D03*
Y371456D03*
X446259Y383268D03*
Y379331D03*
Y375394D03*
Y371456D03*
X458071Y399016D03*
Y395079D03*
Y391142D03*
Y387205D03*
X454134Y399016D03*
Y395079D03*
Y391142D03*
Y387205D03*
X450196Y399016D03*
Y395079D03*
Y391142D03*
Y387205D03*
X446259Y399016D03*
Y395079D03*
Y391142D03*
Y387205D03*
X458071Y414764D03*
Y410827D03*
Y406890D03*
Y402953D03*
X454134Y414764D03*
Y410827D03*
Y406890D03*
Y402953D03*
X450196Y414764D03*
Y410827D03*
Y406890D03*
Y402953D03*
X446259Y414764D03*
Y410827D03*
Y406890D03*
Y402953D03*
X458071Y422638D03*
Y418701D03*
X454134Y422638D03*
Y418701D03*
X450196Y422638D03*
Y418701D03*
X446259Y422638D03*
Y418701D03*
X477756Y336023D03*
Y332086D03*
Y328149D03*
Y324212D03*
X473819Y336023D03*
Y332086D03*
Y328149D03*
Y324212D03*
X469882Y336023D03*
Y332086D03*
Y328149D03*
Y324212D03*
X465945Y336023D03*
Y332086D03*
Y328149D03*
Y324212D03*
X462008Y336023D03*
Y332086D03*
Y328149D03*
Y324212D03*
X477756Y351771D03*
Y347834D03*
Y343897D03*
Y339960D03*
X473819Y351771D03*
Y347834D03*
Y343897D03*
Y339960D03*
X469882Y351771D03*
Y347834D03*
Y343897D03*
Y339960D03*
X465945Y351771D03*
Y347834D03*
Y343897D03*
Y339960D03*
X462008Y351771D03*
Y347834D03*
Y343897D03*
Y339960D03*
X477756Y367519D03*
Y363582D03*
Y359645D03*
Y355708D03*
X473819Y367519D03*
Y363582D03*
Y359645D03*
Y355708D03*
X469882Y367519D03*
Y363582D03*
Y359645D03*
Y355708D03*
X465945Y367519D03*
Y363582D03*
Y359645D03*
Y355708D03*
X462008Y367519D03*
Y363582D03*
Y359645D03*
Y355708D03*
X477756Y383268D03*
Y379331D03*
Y375394D03*
Y371456D03*
X473819Y383268D03*
Y379331D03*
Y375394D03*
Y371456D03*
X469882Y383268D03*
Y379331D03*
Y375394D03*
Y371456D03*
X465945Y383268D03*
Y379331D03*
Y375394D03*
Y371456D03*
X462008Y383268D03*
Y379331D03*
Y375394D03*
Y371456D03*
X477756Y399016D03*
Y395079D03*
Y391142D03*
Y387205D03*
X473819Y399016D03*
Y395079D03*
Y391142D03*
Y387205D03*
X469882Y399016D03*
Y395079D03*
Y391142D03*
Y387205D03*
X465945Y399016D03*
Y395079D03*
Y391142D03*
Y387205D03*
X462008Y399016D03*
Y395079D03*
Y391142D03*
Y387205D03*
X477756Y414764D03*
Y410827D03*
Y406890D03*
Y402953D03*
X473819Y414764D03*
Y410827D03*
Y406890D03*
Y402953D03*
X469882Y414764D03*
Y410827D03*
Y406890D03*
Y402953D03*
X465945Y414764D03*
Y410827D03*
Y406890D03*
Y402953D03*
X462008Y414764D03*
Y410827D03*
Y406890D03*
Y402953D03*
X477756Y422638D03*
Y418701D03*
X473819Y422638D03*
Y418701D03*
X469882Y422638D03*
Y418701D03*
X465945Y422638D03*
Y418701D03*
X462008Y422638D03*
Y418701D03*
X493504Y336023D03*
X489567D03*
Y332086D03*
Y328149D03*
Y324212D03*
X485630Y336023D03*
Y332086D03*
Y328149D03*
Y324212D03*
X481693Y336023D03*
Y332086D03*
Y328149D03*
Y324212D03*
X493504Y351771D03*
Y347834D03*
Y343897D03*
Y339960D03*
X489567Y351771D03*
Y347834D03*
Y343897D03*
Y339960D03*
X485630Y351771D03*
Y347834D03*
Y343897D03*
Y339960D03*
X481693Y351771D03*
Y347834D03*
Y343897D03*
Y339960D03*
X493504Y367519D03*
Y363582D03*
Y359645D03*
Y355708D03*
X489567Y367519D03*
Y363582D03*
Y359645D03*
Y355708D03*
X485630Y367519D03*
Y363582D03*
Y359645D03*
Y355708D03*
X481693Y367519D03*
Y363582D03*
Y359645D03*
Y355708D03*
X493504Y383268D03*
Y379331D03*
Y375394D03*
Y371456D03*
X489567Y383268D03*
Y379331D03*
Y375394D03*
Y371456D03*
X485630Y383268D03*
Y379331D03*
Y375394D03*
Y371456D03*
X481693Y383268D03*
Y379331D03*
Y375394D03*
Y371456D03*
X493504Y399016D03*
Y395079D03*
Y391142D03*
Y387205D03*
X489567Y399016D03*
Y395079D03*
Y391142D03*
Y387205D03*
X485630Y399016D03*
Y395079D03*
Y391142D03*
Y387205D03*
X481693Y399016D03*
Y395079D03*
Y391142D03*
Y387205D03*
X493504Y410827D03*
Y406890D03*
Y402953D03*
X489567Y414764D03*
Y410827D03*
Y406890D03*
Y402953D03*
X485630Y414764D03*
Y410827D03*
Y406890D03*
Y402953D03*
X481693Y414764D03*
Y410827D03*
Y406890D03*
Y402953D03*
X489567Y422638D03*
Y418701D03*
X485630Y422638D03*
Y418701D03*
X481693Y422638D03*
Y418701D03*
X501378Y336023D03*
X497441D03*
X501378Y351771D03*
Y347834D03*
Y343897D03*
Y339960D03*
X497441Y351771D03*
Y347834D03*
Y343897D03*
Y339960D03*
X501378Y367519D03*
Y363582D03*
Y359645D03*
Y355708D03*
X497441Y367519D03*
Y363582D03*
Y359645D03*
Y355708D03*
X501378Y383268D03*
Y379331D03*
Y375394D03*
Y371456D03*
X497441Y383268D03*
Y379331D03*
Y375394D03*
Y371456D03*
X501378Y399016D03*
Y395079D03*
Y391142D03*
Y387205D03*
X497441Y399016D03*
Y395079D03*
Y391142D03*
Y387205D03*
X501378Y410827D03*
Y406890D03*
Y402953D03*
X497441Y410827D03*
Y406890D03*
Y402953D03*
G54D98*
X672962Y456464D03*
X1048968Y155284D03*
X1269468Y444284D03*
G54D89*
X444177Y299000D03*
Y291000D03*
X452977Y295000D03*
G54D99*
X674931Y446821D03*
X672962D03*
X670993D03*
X669025D03*
X667056D03*
X665088D03*
X663119D03*
Y466107D03*
X665088D03*
X667056D03*
X669025D03*
X670993D03*
X672962D03*
X674931D03*
X682805Y446821D03*
X680836D03*
X678868D03*
X676899D03*
Y466107D03*
X678868D03*
X680836D03*
X682805D03*
X1050937Y145641D03*
X1048968D03*
X1046999D03*
X1045031D03*
X1043062D03*
X1041094D03*
X1039125D03*
Y164927D03*
X1041094D03*
X1043062D03*
X1045031D03*
X1046999D03*
X1048968D03*
X1050937D03*
X1058811Y145641D03*
X1056842D03*
X1054874D03*
X1052905D03*
Y164927D03*
X1054874D03*
X1056842D03*
X1058811D03*
X1265531Y434641D03*
X1263562D03*
X1261594D03*
X1259625D03*
Y453927D03*
X1261594D03*
X1263562D03*
X1265531D03*
X1279311Y434641D03*
X1277342D03*
X1275374D03*
X1273405D03*
X1271437D03*
X1269468D03*
X1267499D03*
Y453927D03*
X1269468D03*
X1271437D03*
X1273405D03*
X1275374D03*
X1277342D03*
X1279311D03*
M02*
